G04 ================== begin FILE IDENTIFICATION RECORD ==================*
G04 Layout Name:  9054_F0T_PDB_BD_GPU_F_V04_1213_1550.brd*
G04 Film Name:    bot*
G04 File Format:  Gerber RS274X*
G04 File Origin:  Cadence Allegro 17.2-S081*
G04 Origin Date:  Wed Dec 28 10:19:02 2022*
G04 *
G04 Layer:  DRAWING FORMAT/TITLE_BLOCK_A*
G04 Layer:  PIN/SPECIAL_DRILL*
G04 Layer:  DRAWING FORMAT/TITLE_BLOCK*
G04 Layer:  VIA CLASS/BOTTOM*
G04 Layer:  PIN/BOTTOM*
G04 Layer:  MANUFACTURING/PHOTOPLOT_OUTLINE*
G04 Layer:  ETCH/BOTTOM*
G04 Layer:  DRAWING FORMAT/TITLE_DATA_BOT*
G04 *
G04 Offset:    (0.00 0.00)*
G04 Mirror:    No*
G04 Mode:      Positive*
G04 Rotation:  0*
G04 FullContactRelief:  No*
G04 UndefLineWidth:     6.00*
G04 ================== end FILE IDENTIFICATION RECORD ====================*
%FSLAX25Y25*MOIN*%
%IR0*IPPOS*OFA0.00000B0.00000*MIA0B0*SFA1.00000B1.00000*%
%ADD71O,.123X.074*%
%ADD11C,.02*%
%ADD15C,.03*%
%ADD55R,.13X.095*%
%AMMACRO64*
4,1,5,-.07185,-.1063,
.07185,-.1063,
.07185,.09252,
.05807,.1063,
-.07185,.1063,
-.07185,-.1063,
0.0*
%
%ADD64MACRO64*%
%ADD72C,.061*%
%ADD21C,.07*%
%AMMACRO65*
4,1,8,-.005,.037,
-.005,-.005,
-.014,-.005,
-.014,-.037,
.014,-.037,
.014,-.005,
.005,-.005,
.005,.037,
-.005,.037,
0.0*
%
%ADD65MACRO65*%
%ADD18C,.026*%
%ADD68C,.018*%
%ADD52R,.059X.134*%
%ADD23C,.083*%
%ADD62C,.066*%
%ADD57C,.06015*%
%ADD17C,.039*%
%ADD25C,.085*%
%ADD73C,.086*%
%ADD24C,.095*%
%ADD22R,.07X.07*%
%ADD19C,.04552*%
%ADD61R,.066X.066*%
%ADD60R,.06015X.06015*%
%AMMACRO31*
4,1,28,-.00748,.00052,
-.00984,.00052,
-.00984,.00603,
-.009782,.006705,
-.009607,.007359,
-.009321,.007974,
-.008933,.008529,
-.008455,.009009,
-.0079,.009398,
-.007286,.009685,
-.006632,.009861,
-.005957,.00992,
-.00591,.00992,
.00591,.00992,
.006585,.009869,
.007242,.009701,
.007859,.009421,
.008418,.009039,
.008903,.008565,
.009297,.008015,
.009591,.007404,
.009773,.006751,
.00984,.006077,
.00984,.00603,
.00984,.00052,
.00748,.00052,
.00748,-.00991,
-.00748,-.00991,
-.00748,.00052,
0.0*
%
%ADD31MACRO31*%
%AMMACRO47*
4,1,28,.00052,.00748,
.00052,.00984,
.00603,.00984,
.006705,.009782,
.007359,.009607,
.007974,.009321,
.008529,.008933,
.009009,.008455,
.009398,.0079,
.009685,.007286,
.009861,.006632,
.00992,.005957,
.00992,.00591,
.00992,-.00591,
.009869,-.006585,
.009701,-.007242,
.009421,-.007859,
.009039,-.008418,
.008565,-.008903,
.008015,-.009297,
.007404,-.009591,
.006751,-.009773,
.006077,-.00984,
.00603,-.00984,
.00052,-.00984,
.00052,-.00748,
-.00991,-.00748,
-.00991,.00748,
.00052,.00748,
0.0*
%
%ADD47MACRO47*%
%ADD20R,.04552X.04552*%
%AMMACRO30*
4,1,28,-.00748,-.00051,
-.00984,-.00051,
-.00984,-.00602,
-.009782,-.006695,
-.009607,-.007349,
-.009321,-.007964,
-.008933,-.008519,
-.008455,-.008998,
-.0079,-.009388,
-.007287,-.009675,
-.006632,-.009851,
-.005958,-.00991,
-.00591,-.00991,
.00591,-.00991,
.006585,-.009859,
.007242,-.009691,
.007859,-.009411,
.008418,-.009029,
.008903,-.008555,
.009297,-.008005,
.00959,-.007394,
.009773,-.006742,
.00984,-.006068,
.00984,-.00602,
.00984,-.00051,
.00748,-.00051,
.00748,.00992,
-.00748,.00992,
-.00748,-.00051,
0.0*
%
%ADD30MACRO30*%
%AMMACRO46*
4,1,28,-.00051,.00748,
-.00051,.00984,
-.00602,.00984,
-.006695,.009782,
-.007349,.009607,
-.007964,.009321,
-.008519,.008933,
-.008998,.008455,
-.009388,.0079,
-.009675,.007287,
-.009851,.006632,
-.00991,.005958,
-.00991,.00591,
-.00991,-.00591,
-.009859,-.006585,
-.009691,-.007242,
-.009411,-.007859,
-.009029,-.008418,
-.008555,-.008903,
-.008005,-.009297,
-.007394,-.00959,
-.006742,-.009773,
-.006068,-.00984,
-.00602,-.00984,
-.00051,-.00984,
-.00051,-.00748,
.00992,-.00748,
.00992,.00748,
-.00051,.00748,
0.0*
%
%ADD46MACRO46*%
%ADD49R,.11X.22*%
%ADD44R,.03X.011*%
%ADD50O,.033X.012*%
%ADD43R,.011X.03*%
%ADD51O,.012X.033*%
%ADD63R,.032X.022*%
%ADD53R,.04X.05*%
%ADD33R,.02X.018*%
%ADD41R,.028X.011*%
%ADD32R,.034X.032*%
%ADD48R,.063X.04*%
%ADD42R,.011X.028*%
%ADD66R,.024X.017*%
%AMMACRO40*
4,1,5,.07185,.1063,
-.07185,.1063,
-.07185,-.09252,
-.05807,-.1063,
.07185,-.1063,
.07185,.1063,
0.0*
%
%ADD40MACRO40*%
%ADD67R,.017X.024*%
%ADD54R,.135X.128*%
%ADD26R,.032X.028*%
%ADD36R,.046X.015*%
%ADD27R,.028X.032*%
%ADD37R,.054X.044*%
%ADD10C,.125*%
%ADD70C,.414*%
%ADD59C,.315*%
%ADD56R,.062X.046*%
%ADD34R,.044X.054*%
%ADD14O,.355X.552*%
%ADD69R,.059X.014*%
%ADD45R,.046X.062*%
%ADD12O,.394X.67*%
%AMMACRO35*
4,1,8,.005,-.037,
.005,.005,
.014,.005,
.014,.037,
-.014,.037,
-.014,.005,
-.005,.005,
-.005,-.037,
.005,-.037,
0.0*
%
%ADD35MACRO35*%
%ADD16C,.158*%
%AMMACRO39*
4,1,28,-.00052,-.00748,
-.00052,-.00984,
-.00603,-.00984,
-.006705,-.009782,
-.007359,-.009607,
-.007974,-.009321,
-.008529,-.008933,
-.009009,-.008455,
-.009398,-.0079,
-.009685,-.007286,
-.009861,-.006632,
-.00992,-.005957,
-.00992,-.00591,
-.00992,.00591,
-.009869,.006585,
-.009701,.007242,
-.009421,.007859,
-.009039,.008418,
-.008565,.008903,
-.008015,.009297,
-.007404,.009591,
-.006751,.009773,
-.006077,.00984,
-.00603,.00984,
-.00052,.00984,
-.00052,.00748,
.00991,.00748,
.00991,-.00748,
-.00052,-.00748,
0.0*
%
%ADD39MACRO39*%
%AMMACRO29*
4,1,28,.00748,-.00052,
.00984,-.00052,
.00984,-.00603,
.009782,-.006705,
.009607,-.007359,
.009321,-.007974,
.008933,-.008529,
.008455,-.009009,
.0079,-.009398,
.007286,-.009685,
.006632,-.009861,
.005957,-.00992,
.00591,-.00992,
-.00591,-.00992,
-.006585,-.009869,
-.007242,-.009701,
-.007859,-.009421,
-.008418,-.009039,
-.008903,-.008565,
-.009297,-.008015,
-.009591,-.007404,
-.009773,-.006751,
-.00984,-.006077,
-.00984,-.00603,
-.00984,-.00052,
-.00748,-.00052,
-.00748,.00991,
.00748,.00991,
.00748,-.00052,
0.0*
%
%ADD29MACRO29*%
%AMMACRO38*
4,1,28,.00051,-.00748,
.00051,-.00984,
.00602,-.00984,
.006695,-.009782,
.007349,-.009607,
.007964,-.009321,
.008519,-.008933,
.008998,-.008455,
.009388,-.0079,
.009675,-.007287,
.009851,-.006632,
.00991,-.005958,
.00991,-.00591,
.00991,.00591,
.009859,.006585,
.009691,.007242,
.009411,.007859,
.009029,.008418,
.008555,.008903,
.008005,.009297,
.007394,.00959,
.006742,.009773,
.006068,.00984,
.00602,.00984,
.00051,.00984,
.00051,.00748,
-.00992,.00748,
-.00992,-.00748,
.00051,-.00748,
0.0*
%
%ADD38MACRO38*%
%AMMACRO28*
4,1,28,.00748,.00051,
.00984,.00051,
.00984,.00602,
.009782,.006695,
.009607,.007349,
.009321,.007964,
.008933,.008519,
.008455,.008998,
.0079,.009388,
.007287,.009675,
.006632,.009851,
.005958,.00991,
.00591,.00991,
-.00591,.00991,
-.006585,.009859,
-.007242,.009691,
-.007859,.009411,
-.008418,.009029,
-.008903,.008555,
-.009297,.008005,
-.00959,.007394,
-.009773,.006742,
-.00984,.006068,
-.00984,.00602,
-.00984,.00051,
-.00748,.00051,
-.00748,-.00992,
.00748,-.00992,
.00748,.00051,
0.0*
%
%ADD28MACRO28*%
%ADD74C,.01*%
%ADD75C,.011*%
%ADD76C,.014*%
%ADD77C,.015*%
%ADD78C,.025*%
%ADD79C,.006*%
%ADD80C,.0068*%
%ADD82C,.03004*%
%ADD88C,.03006*%
%ADD81C,.03604*%
%ADD93C,.07026*%
%ADD90C,.03606*%
%ADD86C,.22004*%
%ADD91C,.1171*%
%ADD89C,.32504*%
%ADD87C,.11706*%
%ADD85C,.12806*%
%ADD92C,.17604*%
%ADD83C,.16506*%
%ADD84C,.19806*%
G75*
%LPD*%
G75*
G36*
G01X1437008Y673787D02*
X1590551D01*
G02X1608236Y656102I0J-17685D01*
G01Y642913D01*
G03X1629921Y621228I21685J0D01*
G01X1712598D01*
G02X1730283Y603543I0J-17685D01*
G01Y538465D01*
G03X1751968Y516780I21685J0D01*
G01X1854331D01*
G02X1872016Y499095I0J-17685D01*
G01Y85709D01*
G02X1854331Y68024I-17685J0D01*
G01X1751968D01*
G03X1730283Y46339I1J-21686D01*
G01Y19685D01*
G02X1712598Y2000I-17685J0D01*
G01X1497932D01*
Y3999D01*
X1712598D01*
G03X1728284Y19685I0J15686D01*
G01Y46339D01*
G02X1751968Y70023I23685J-1D01*
G01X1854331D01*
G03X1870017Y85709I0J15686D01*
G01Y499095D01*
G03X1854331Y514781I-15686J0D01*
G01X1751968D01*
G02X1728284Y538465I1J23684D01*
G01Y603543D01*
G03X1712598Y619229I-15686J0D01*
G01X1629921D01*
G02X1606237Y642913I0J23684D01*
G01Y656102D01*
G03X1590551Y671788I-15686J0D01*
G01X1437008D01*
G03X1421322Y656102I0J-15686D01*
G01Y635039D01*
G02X1405512Y619229I-15810J0D01*
G01X1403543D01*
G03X1387857Y603543I0J-15686D01*
G01Y435039D01*
G02X1354331Y401513I-33526J0D01*
G01X377952D01*
G02X344426Y435039I1J33527D01*
G01Y603543D01*
G03X328740Y619229I-15686J0D01*
G01X326772D01*
G02X310962Y635039I0J15810D01*
G01Y656102D01*
G03X295276Y671788I-15686J0D01*
G01X141732D01*
G03X126046Y656102I0J-15686D01*
G01Y642913D01*
G02X102362Y619229I-23684J0D01*
G01X19685D01*
G03X3999Y603543I0J-15686D01*
G01Y19685D01*
G03X19685Y3999I15686J0D01*
G01X226571D01*
Y2000D01*
X19685D01*
G02X2000Y19685I0J17685D01*
G01Y603543D01*
G02X19685Y621228I17685J0D01*
G01X102362D01*
G03X124047Y642913I0J21685D01*
G01Y656102D01*
G02X141732Y673787I17685J0D01*
G01X295276D01*
G02X312961Y656102I0J-17685D01*
G01Y635039D01*
G03X326772Y621228I13811J0D01*
G01X328740D01*
G02X346425Y603543I0J-17685D01*
G01Y435039D01*
G03X377952Y403512I31528J1D01*
G01X1354331D01*
G03X1385858Y435039I0J31527D01*
G01Y603543D01*
G02X1403543Y621228I17685J0D01*
G01X1405512D01*
G03X1419323Y635039I0J13811D01*
G01Y656102D01*
G02X1437008Y673787I17685J0D01*
G37*
G36*
G01X13083Y612500D02*
X115917D01*
G02X116059Y612441I0J-200D01*
G01X119441Y609059D01*
G02X119500Y608917I-141J-142D01*
G01Y152083D01*
G03X119559Y151941I200J0D01*
G01X135019Y136481D01*
G02X135060Y136257I-141J-142D01*
G01X134881Y135858D01*
X134775Y135795D01*
X134712Y135799D01*
G03X134600Y135802I-104J-1799D01*
G03X136402Y134000I0J-1802D01*
G03X136399Y134112I-1802J8D01*
G01X136395Y134175D01*
X136458Y134281D01*
X136857Y134460D01*
G02X137081Y134419I82J-182D01*
G01X148304Y123196D01*
G03X148446Y123137I142J141D01*
G01X215672D01*
G02X215814Y123078I0J-200D01*
G01X234750Y104142D01*
G03X234892Y104083I142J141D01*
G01X288549D01*
G02X288691Y104024I0J-200D01*
G01X308344Y84371D01*
G03X308486Y84312I142J141D01*
G01X350257D01*
G02X350399Y84253I0J-200D01*
G01X390139Y44513D01*
G03X390281Y44454I142J141D01*
G01X570410D01*
X571956Y46000D01*
X630404D01*
X641635Y57231D01*
Y99783D01*
G02X641694Y99925I200J0D01*
G01X643055Y101286D01*
G02X643197Y101345I142J-141D01*
G01X811041D01*
G02X811228Y101216I0J-200D01*
G01X811383Y100807D01*
X811354Y100688D01*
X811306Y100646D01*
G03X805835Y88485I10781J-12161D01*
G01Y88484D01*
G03X838339I16252J0D01*
G01Y88485D01*
G03X832868Y100646I-16252J0D01*
G01X832820Y100688D01*
X832791Y100807D01*
X832946Y101216D01*
G02X833133Y101345I187J-71D01*
G01X859051D01*
G02X859193Y101286I0J-200D01*
G01X860941Y99538D01*
G02X861000Y99396I-141J-142D01*
G01Y37640D01*
G02X860941Y37498I-200J0D01*
G01X859842Y36399D01*
G02X859700Y36340I-142J141D01*
G01X240423D01*
G03X240281Y36281I0J-200D01*
G01X212559Y8559D01*
G02X212417Y8500I-142J141D01*
G01X17583D01*
G02X17441Y8559I0J200D01*
G01X8559Y17441D01*
G02X8500Y17583I141J142D01*
G01Y607917D01*
G02X8559Y608059I200J0D01*
G01X12941Y612441D01*
G02X13083Y612500I142J-141D01*
G37*
G36*
G01X141732Y666846D02*
X145979D01*
G02X146133Y666774I0J-200D01*
G01X146359Y666505D01*
X146381Y666421D01*
X146373Y666376D01*
G03X146226Y664685I9631J-1689D01*
G03X147019Y660827I9778J-1D01*
G01X147035Y660748D01*
X147019Y660669D01*
G03X146226Y656811I8985J-3857D01*
G03X147019Y652953I9778J-1D01*
G01X147035Y652874D01*
X147019Y652795D01*
G03X146226Y648937I8985J-3857D01*
G03X147019Y645079I9778J-1D01*
G01X147035Y645000D01*
X147019Y644921D01*
G03X146226Y641063I8985J-3857D01*
G03X147019Y637205I9778J-1D01*
G01X147035Y637126D01*
X147019Y637047D01*
G03X146226Y633189I8985J-3857D01*
G03X147019Y629331I9778J-1D01*
G01X147035Y629252D01*
X147019Y629173D01*
G03X146226Y625315I8985J-3857D01*
G03X147019Y621457I9778J-1D01*
G01X147035Y621378D01*
X147019Y621299D01*
G03X146226Y617441I8985J-3857D01*
G03X147019Y613583I9778J-1D01*
G01X147035Y613504D01*
X147019Y613425D01*
G03X146226Y609567I8985J-3857D01*
G03X147019Y605709I9778J-1D01*
G01X147035Y605630D01*
X147019Y605551D01*
G03X146226Y601694I8985J-3857D01*
G01Y601693D01*
G03X147703Y596526I9778J0D01*
G01X147718Y596502D01*
X147733Y596448D01*
Y592144D01*
G03X147792Y592002I200J0D01*
G01X149497Y590297D01*
G03X149639Y590238I142J141D01*
G01X178439D01*
G03X178581Y590297I0J200D01*
G01X179916Y591632D01*
G03X179975Y591774I-141J142D01*
G01Y633144D01*
G02X180034Y633286I200J0D01*
G01X183189Y636441D01*
G02X183331Y636500I142J-141D01*
G01X202619D01*
G02X202795Y636394I-1J-200D01*
G03X212953I5079J2700D01*
G02X213129Y636500I177J-94D01*
G01X303260D01*
G02X303460Y636300I0J-200D01*
G01Y635039D01*
G03X304007Y630022I23312J3D01*
G01X304008Y630014D01*
G03X304262Y628977I8369J1500D01*
G01X304264Y628970D01*
G03X304840Y627138I22508J6070D01*
G01X304852Y627071D01*
Y608485D01*
G02X304793Y608343I-200J0D01*
G01X288196Y591746D01*
G03X288137Y591604I141J-142D01*
G01Y547638D01*
G03X288196Y547496I200J0D01*
G01X300879Y534813D01*
G03X301021Y534754I142J141D01*
G01X329400D01*
G02X329542Y534695I0J-200D01*
G01X334941Y529296D01*
G02X335000Y529154I-141J-142D01*
G01Y360683D01*
G03X335059Y360541I200J0D01*
G01X401843Y293757D01*
X440418D01*
G03X440560Y293698I142J141D01*
G01X467524D01*
X468338Y292884D01*
Y275485D01*
X467255Y274402D01*
X426502D01*
X425500Y273400D01*
Y250800D01*
X426943Y249357D01*
X434343D01*
X434402Y249298D01*
X467524D01*
X468338Y248484D01*
Y231085D01*
X467255Y230002D01*
X425798D01*
X422819Y232981D01*
X419949D01*
G03X410451I-4749J-8482D01*
G01X408700D01*
G03X408106Y233002I-597J-8482D01*
G01X408100D01*
G03X399598Y224500I0J-8502D01*
G03X404175Y216958I8502J0D01*
G01X405733Y215400D01*
X408200D01*
Y206450D01*
X408596Y206054D01*
X409694Y204957D01*
X440418D01*
G03X440560Y204898I142J141D01*
G01X467524D01*
X468338Y204084D01*
Y186685D01*
X467255Y185602D01*
X423405D01*
G03X415200Y189979I-8205J-5502D01*
G03X410166Y188600I0J-9879D01*
G01X408284D01*
G03X408100Y188602I-184J-8501D01*
G03X407916Y188600I0J-8502D01*
G01X407700D01*
Y188593D01*
G03X399598Y180100I400J-8493D01*
G03X404445Y172424I8502J0D01*
G01X405969Y170900D01*
X408188D01*
Y162879D01*
X410510Y160557D01*
X440418D01*
G03X440560Y160498I142J141D01*
G01X467524D01*
X468338Y159684D01*
Y142285D01*
X467255Y141202D01*
X427102D01*
X425400Y139500D01*
Y117800D01*
X427043Y116157D01*
X440418D01*
G03X440560Y116098I142J141D01*
G01X467524D01*
X468338Y115284D01*
Y97885D01*
X467255Y96802D01*
X427402D01*
X425400Y94800D01*
Y73000D01*
X426800Y71600D01*
X440261D01*
X440418Y71757D01*
G03X440560Y71698I142J141D01*
G01X467524D01*
X468338Y70884D01*
Y53485D01*
X467255Y52402D01*
X403068D01*
G03X396216Y55678I-6852J-5528D01*
G03X396121Y55677I45J-8803D01*
G01X390685Y61113D01*
Y61165D01*
X356382Y95468D01*
G03X356240Y95527I-142J-141D01*
G01X322531D01*
G02X322389Y95586I0J200D01*
G01X304742Y113233D01*
G03X304600Y113292I-142J-141D01*
G01X239656D01*
G02X239514Y113351I0J200D01*
G01X218924Y133941D01*
G03X218782Y134000I-142J-141D01*
G01X158666D01*
G02X158524Y134059I0J200D01*
G01X143401Y149182D01*
X143371Y149263D01*
X143375Y149307D01*
G03X143402Y149992I-8775J689D01*
G01Y150000D01*
G03X134600Y158802I-8802J0D01*
G03X134432Y158800I21J-8802D01*
G01X134391D01*
X134317Y158829D01*
X134084Y159058D01*
G02X134024Y159200I140J143D01*
G01Y587858D01*
G02X134083Y588000I200J0D01*
G01Y661536D01*
G02X134096Y661608I200J1D01*
G02X141732Y666846I7636J-2947D01*
G37*
G36*
G01X155310Y667320D02*
X304133D01*
G02X304275Y667261I0J-200D01*
G01X305668Y665868D01*
G02X305727Y665726I-141J-142D01*
G01Y648070D01*
G02X305668Y647928I-200J0D01*
G01X304463Y646723D01*
G02X304321Y646664I-142J141D01*
G01X167838D01*
G03X167696Y646605I0J-200D01*
G01X166240Y645149D01*
G03X166181Y645007I141J-142D01*
G01Y600525D01*
G02X166122Y600383I-200J0D01*
G01X165107Y599368D01*
G02X164965Y599309I-142J141D01*
G01X155370D01*
G02X155228Y599368I0J200D01*
G01X154814Y599782D01*
X154785Y599875D01*
X154794Y599925D01*
G03X154955Y601693I-9617J1767D01*
G03X154494Y604661I-9778J1D01*
G02X154486Y604744I190J60D01*
G03Y606516I-7650J886D01*
G02X154494Y606599I198J23D01*
G03X154955Y609567I-9317J2967D01*
G03X154494Y612535I-9778J1D01*
G02X154486Y612618I190J60D01*
G03Y614390I-7650J886D01*
G02X154494Y614473I198J23D01*
G03X154955Y617441I-9317J2967D01*
G03X154494Y620409I-9778J1D01*
G02X154486Y620492I190J60D01*
G03Y622264I-7650J886D01*
G02X154494Y622347I198J23D01*
G03X154955Y625315I-9317J2967D01*
G03X154494Y628283I-9778J1D01*
G02X154486Y628366I190J60D01*
G03Y630138I-7650J886D01*
G02X154494Y630221I198J23D01*
G03X154955Y633189I-9317J2967D01*
G03X154494Y636157I-9778J1D01*
G02X154486Y636240I190J60D01*
G03Y638012I-7650J886D01*
G02X154494Y638095I198J23D01*
G03X154955Y641063I-9317J2967D01*
G03X154494Y644031I-9778J1D01*
G02X154486Y644114I190J60D01*
G03Y645886I-7650J886D01*
G02X154494Y645969I198J23D01*
G03X154955Y648937I-9317J2967D01*
G03X154494Y651905I-9778J1D01*
G02X154486Y651988I190J60D01*
G03Y653760I-7650J886D01*
G02X154494Y653843I198J23D01*
G03X154955Y656811I-9317J2967D01*
G03X154494Y659779I-9778J1D01*
G02X154486Y659862I190J60D01*
G03Y661634I-7650J886D01*
G02X154494Y661717I198J23D01*
G03X154955Y664685I-9317J2967D01*
G03X154743Y666708I-9778J-2D01*
G01X154733Y666758D01*
X154761Y666854D01*
X155168Y667261D01*
G02X155310Y667320I142J-141D01*
G37*
G36*
G01X881120Y28838D02*
X1423075D01*
G02X1423216Y28780I0J-200D01*
G01X1424451Y27545D01*
G02X1424510Y27403I-141J-142D01*
G01Y15333D01*
G03X1424569Y15191I200J0D01*
G01X1424652Y15108D01*
X1424682Y15043D01*
X1424684Y15007D01*
G03X1437098Y11862I6733J505D01*
G02X1437349Y11935I168J-109D01*
G03X1441417Y11049I4067J8892D01*
G03X1446317Y12365I1J9778D01*
G02X1446517I100J-173D01*
G03X1451417Y11049I4899J8462D01*
G03X1453397Y11252I-2J9778D01*
G01X1453442Y11261D01*
X1453528Y11240D01*
X1453804Y11015D01*
G02X1453878Y10860I-126J-155D01*
G01Y4811D01*
G02X1453819Y4669I-200J0D01*
G01X1452944Y3794D01*
G02X1452802Y3735I-142J141D01*
G01X324438D01*
G02X324296Y3794I0J200D01*
G01X322431Y5659D01*
G02X322372Y5801I141J142D01*
G01Y27152D01*
G02X322431Y27294I200J0D01*
G01X323917Y28780D01*
G02X324058Y28838I141J-142D01*
G01X854019D01*
X854132Y28736D01*
X854140Y28658D01*
G03X862212Y21007I8460J842D01*
G02X862315Y20972I-10J-200D01*
G03X867100Y19498I4785J7028D01*
G03X871805Y20919I-1J8502D01*
G02X871930Y20951I109J-167D01*
G03X872533Y20930I597J8481D01*
G03X881000Y28657I0J8502D01*
G01X881007Y28735D01*
X881120Y28838D01*
G37*
G36*
G01X350183Y399000D02*
X458917D01*
X580417D01*
X583917Y395500D01*
G02X584059Y395441I0J-200D01*
G01X613941Y365559D01*
G03X614083Y365500I142J141D01*
G01X629417D01*
G03X629559Y365559I0J200D01*
G01X648475Y384475D01*
X769798D01*
G02X769940Y384416I0J-200D01*
G01X824569Y329787D01*
G02X824607Y329556I-141J-142D01*
G01X824599Y329541D01*
G03X822091Y329736I-2510J-16057D01*
G01X822087D01*
G03Y297232I0J-16252D01*
G03X826784Y297926I-1J16252D01*
G01Y217829D01*
X825132Y216177D01*
X719515D01*
X718733Y216959D01*
Y232650D01*
X719580Y233497D01*
X738138D01*
X740100Y235459D01*
Y311400D01*
X700858Y350642D01*
X668469D01*
G03X668327Y350701I-142J-141D01*
G01X637683D01*
G03X632186Y351920I-5497J-11785D01*
G03X626689Y350701I0J-13004D01*
G01X612739D01*
G03X612597Y350642I0J-200D01*
G01X612407D01*
G03X612265Y350583I0J-200D01*
G01X597898Y336216D01*
X417899D01*
G03X417757Y336157I0J-200D01*
G01X406159Y324559D01*
G02X406017Y324500I-142J141D01*
G01X383183D01*
G02X383041Y324559I0J200D01*
G01X347659Y359941D01*
G02X347600Y360083I141J142D01*
G01Y396417D01*
G02X347659Y396559I200J0D01*
G01X350041Y398941D01*
G02X350183Y399000I142J-141D01*
G37*
G36*
G01X487384Y181700D02*
X535484D01*
X536884Y180300D01*
Y59100D01*
X534284Y56500D01*
X488784D01*
X486284Y59000D01*
Y180600D01*
X487384Y181700D01*
G37*
G36*
G01Y314900D02*
X535484D01*
X536884Y313500D01*
Y185798D01*
X535086Y184000D01*
X487584D01*
X486284Y185300D01*
Y313800D01*
X487384Y314900D01*
G37*
G36*
G01X700509Y224201D02*
X709750D01*
X710101Y223850D01*
Y220036D01*
X708873Y218808D01*
X703838D01*
X700587Y215557D01*
Y215534D01*
X696252D01*
X684133Y203415D01*
X678547D01*
X675872Y200740D01*
Y170609D01*
X683747Y162734D01*
X756015D01*
X778981Y185700D01*
X825584D01*
X826725Y184559D01*
G02X826784Y184417I-141J-142D01*
G01Y118296D01*
G02X826725Y118154I-200J0D01*
G01X823675Y115104D01*
G02X823533Y115045I-142J141D01*
G01X637425D01*
X629600Y107220D01*
Y63800D01*
X623800Y58000D01*
X567554D01*
X565554Y60000D01*
Y124089D01*
X566637Y125172D01*
X576988D01*
X581584Y129768D01*
X585180D01*
X586568Y131156D01*
Y178385D01*
X627143Y218960D01*
X695268D01*
X700509Y224201D01*
G37*
G36*
G01X590124Y265795D02*
X594564D01*
X594660Y265699D01*
Y264601D01*
X590387Y260328D01*
Y246923D01*
X591318Y245992D01*
X597257D01*
X597447Y245802D01*
Y240443D01*
X596073Y239069D01*
Y238877D01*
Y237827D01*
Y232305D01*
X595670Y231902D01*
X589365D01*
X587608Y233659D01*
Y263279D01*
X590124Y265795D01*
G37*
G36*
G01X589027Y315982D02*
X596925D01*
X597184Y315723D01*
Y309029D01*
X596606Y308451D01*
Y288139D01*
X596474Y288007D01*
X595315D01*
X595236Y288086D01*
Y293602D01*
X588381Y300457D01*
Y315336D01*
X589027Y315982D01*
G37*
G36*
G01X603270Y264211D02*
X604157D01*
X604348Y264020D01*
Y261232D01*
X604318Y261202D01*
Y260700D01*
X604000Y260382D01*
Y255600D01*
X604318Y255282D01*
Y247841D01*
X605728Y246431D01*
Y244640D01*
X603808Y242720D01*
Y232397D01*
X603449Y232038D01*
X599302D01*
X599146Y232194D01*
Y237746D01*
X600751Y239351D01*
Y258712D01*
X603159Y261120D01*
Y264100D01*
X603270Y264211D01*
G37*
G36*
G01X645185Y339230D02*
X703043D01*
G02X703076Y339227I-2J-200D01*
G02X703183Y339173I-32J-197D01*
G01X708216Y334140D01*
G02X708275Y333998I-141J-142D01*
G01Y302575D01*
X698334Y292634D01*
Y289913D01*
X698304Y289839D01*
X698275Y289811D01*
X696805Y288341D01*
G03X696746Y288199I141J-142D01*
G01Y267116D01*
G02X696546Y266916I-200J0D01*
G01X685852D01*
G02X685652Y267116I0J200D01*
G01Y288867D01*
G02X685852Y289067I200J0D01*
G01X696090D01*
G03X696232Y289126I0J200D01*
G01X697032Y289926D01*
G03X697091Y290068I-141J142D01*
G01Y293939D01*
G02X697150Y294081I200J0D01*
G01X699583Y296514D01*
G03X699642Y296656I-141J142D01*
G01Y307300D01*
G02X699842Y307500I200J0D01*
G01X701928D01*
G03X702070Y307559I0J200D01*
G01X704829Y310318D01*
G03X704888Y310460I-141J142D01*
G01Y326751D01*
G03X704829Y326893I-200J0D01*
G01X702896Y328826D01*
G03X702754Y328885I-142J-141D01*
G01X685064D01*
G03X684922Y328826I0J-200D01*
G01X683855Y327759D01*
G03X683796Y327617I141J-142D01*
G01Y308954D01*
G03X683855Y308812I200J0D01*
G01X685007Y307660D01*
G03X685149Y307601I142J141D01*
G01X689468D01*
G02X689501Y307598I-2J-200D01*
G02X689608Y307544I-32J-197D01*
G01X689830Y307322D01*
G02X689889Y307180I-141J-142D01*
G01Y302990D01*
X689859Y302916D01*
X689830Y302888D01*
X689525Y302583D01*
G02X689383Y302524I-142J141D01*
G01X680497D01*
X680423Y302554D01*
X680395Y302583D01*
X673048Y309930D01*
G02X672989Y310072I141J142D01*
G01Y316428D01*
G03X672930Y316570I-200J0D01*
G01X672059Y317441D01*
G03X671917Y317500I-142J-141D01*
G01X664245D01*
G03X664103Y317441I0J-200D01*
G01X658088Y311426D01*
G03X658029Y311284I141J-142D01*
G01Y302479D01*
G03X658088Y302337I200J0D01*
G01X658646Y301779D01*
G03X658788Y301720I142J141D01*
G01X665646D01*
G02X665679Y301717I-2J-200D01*
G02X665786Y301663I-32J-197D01*
G01X665839Y301610D01*
G02X665898Y301468I-141J-142D01*
G01Y299731D01*
X665868Y299657D01*
X665839Y299629D01*
X665746Y299536D01*
G02X665604Y299477I-142J141D01*
G01X658828D01*
G03X658686Y299418I0J-200D01*
G01X658212Y298944D01*
G03X658153Y298802I141J-142D01*
G01Y285935D01*
G02X658048Y285759I-200J0D01*
G03Y282241I952J-1759D01*
G02X658153Y282065I-95J-176D01*
G01Y276162D01*
G03X658212Y276020I200J0D01*
G01X658644Y275588D01*
G03X658786Y275529I142J141D01*
G01X666913D01*
G02X666946Y275526I-2J-200D01*
G02X667053Y275472I-32J-197D01*
G01X667106Y275419D01*
G02X667165Y275277I-141J-142D01*
G01Y272652D01*
X667135Y272578D01*
X667106Y272550D01*
X666928Y272372D01*
G02X666786Y272313I-142J141D01*
G01X662890D01*
G03X662748Y272254I0J-200D01*
G01X662401Y271907D01*
G03X662342Y271765I141J-142D01*
G01Y266137D01*
X662312Y266063D01*
X662283Y266035D01*
X662273Y266025D01*
X662245Y265996D01*
X662171Y265966D01*
X653149D01*
G03X653007Y265907I0J-200D01*
G01X652659Y265559D01*
G03X652600Y265417I141J-142D01*
G01Y260083D01*
G03X652659Y259941I200J0D01*
G01X653006Y259594D01*
G03X653148Y259535I142J141D01*
G01X663949D01*
X664192Y259292D01*
Y253644D01*
X664112Y253564D01*
G02X663970Y253505I-142J141D01*
G01X654933D01*
G03X654791Y253446I0J-200D01*
G01X651777Y250432D01*
G02X651635Y250373I-142J141D01*
G01X640591D01*
X640517Y250403D01*
X640489Y250432D01*
X640184Y250737D01*
G02X640125Y250879I141J142D01*
G01Y256341D01*
G02X640184Y256483I200J0D01*
G01X642901Y259200D01*
G03X642960Y259342I-141J142D01*
G01Y270387D01*
G03X642901Y270529I-200J0D01*
G01X641036Y272394D01*
G03X640894Y272453I-142J-141D01*
G01X637340D01*
X637266Y272483D01*
X637238Y272512D01*
X637162Y272588D01*
G02X637103Y272730I141J142D01*
G01Y274144D01*
G02X637162Y274286I200J0D01*
G01X637337Y274461D01*
G02X637479Y274520I142J-141D01*
G01X640635D01*
G03X640777Y274579I0J200D01*
G01X641109Y274911D01*
G03X641168Y275053I-141J142D01*
G01Y282652D01*
G03X641109Y282794I-200J0D01*
G01X640451Y283452D01*
G03X640309Y283511I-142J-141D01*
G01X637326D01*
X637252Y283541D01*
X637224Y283570D01*
X637213Y283581D01*
X637184Y283609D01*
X637154Y283683D01*
Y290505D01*
G02X637213Y290647I200J0D01*
G01X637365Y290799D01*
G02X637507Y290858I142J-141D01*
G01X640774D01*
G03X640916Y290917I0J200D01*
G01X641614Y291615D01*
G03X641673Y291757I-141J142D01*
G01Y299139D01*
G02X641732Y299281I200J0D01*
G01X644411Y301960D01*
G03X644470Y302102I-141J142D01*
G01Y306854D01*
G03X644411Y306996I-200J0D01*
G01X643738Y307669D01*
G02X643679Y307811I141J142D01*
G01Y311084D01*
G03X643620Y311226I-200J0D01*
G01X641954Y312892D01*
G03X641812Y312951I-142J-141D01*
G01X610010D01*
G03X609868Y312892I0J-200D01*
G01X608928Y311952D01*
G03X608869Y311810I141J-142D01*
G01Y309419D01*
X608839Y309345D01*
X608810Y309317D01*
X606304Y306811D01*
G03X606245Y306669I141J-142D01*
G01Y297931D01*
G03X606304Y297789I200J0D01*
G01X610226Y293867D01*
G02X610285Y293725I-141J-142D01*
G01Y286950D01*
G03X610344Y286808I200J0D01*
G01X610392Y286760D01*
G03X610534Y286701I142J141D01*
G01X617258D01*
G02X617458Y286501I0J-200D01*
G01Y265489D01*
X617428Y265415D01*
X617399Y265387D01*
X617310Y265298D01*
G02X617168Y265239I-142J141D01*
G01X614446D01*
G03X614304Y265180I0J-200D01*
G01X614267Y265143D01*
G03X614208Y265001I141J-142D01*
G01Y252995D01*
X614178Y252921D01*
X614149Y252893D01*
X609646Y248390D01*
G03X609587Y248248I141J-142D01*
G01Y238366D01*
X609557Y238292D01*
X609528Y238264D01*
X609497Y238233D01*
G02X609355Y238174I-142J141D01*
G01X606443D01*
G02X606243Y238374I0J200D01*
G01Y241661D01*
G02X606302Y241803I200J0D01*
G01X606564Y242065D01*
G03X606623Y242207I-141J142D01*
G01Y250363D01*
G02X606682Y250505I200J0D01*
G01X606712Y250535D01*
G02X606854Y250594I142J-141D01*
G01X608698D01*
G03X608840Y250653I0J200D01*
G01X611875Y253688D01*
G03X611934Y253830I-141J142D01*
G01Y258762D01*
G03X611875Y258904I-200J0D01*
G01X611025Y259754D01*
G02X610966Y259896I141J142D01*
G01Y264962D01*
G03X610907Y265104I-200J0D01*
G01X610804Y265207D01*
G03X610662Y265266I-142J-141D01*
G01X604322D01*
X604248Y265296D01*
X604220Y265325D01*
X602953Y266592D01*
G02X602894Y266734I141J142D01*
G01Y286505D01*
G02X603094Y286705I200J0D01*
G01X608696D01*
G03X608838Y286764I0J200D01*
G01X608960Y286886D01*
G03X609019Y287028I-141J142D01*
G01Y292717D01*
G03X608960Y292859I-200J0D01*
G01X607038Y294781D01*
G03X606896Y294840I-142J-141D01*
G01X605688D01*
X605614Y294870D01*
X605586Y294899D01*
X603493Y296992D01*
G02X603434Y297134I141J142D01*
G01Y307951D01*
G02X603493Y308093I200J0D01*
G01X604125Y308725D01*
G03X604184Y308867I-141J142D01*
G01Y323015D01*
G02X604243Y323157I200J0D01*
G01X619207Y338121D01*
G03X632186Y325914I12979J796D01*
G03X645189Y338917I0J13003D01*
G03X645185Y339230I-13003J-10D01*
G37*
G36*
G01X595312Y264052D02*
X596444D01*
X596518Y263978D01*
Y257784D01*
X597278Y257024D01*
Y249000D01*
X591859D01*
X591777Y249082D01*
Y257424D01*
X595207Y260854D01*
Y263947D01*
X595312Y264052D01*
G37*
G36*
G01X625684Y227500D02*
X621200D01*
X620588Y228112D01*
Y234500D01*
Y236426D01*
X621142Y236980D01*
X625601D01*
X626184Y236397D01*
Y234000D01*
Y228000D01*
X625684Y227500D01*
G37*
G36*
G01X638015Y227758D02*
X632689D01*
X632370Y228077D01*
Y242112D01*
X632944Y242686D01*
X643278D01*
X643406Y242558D01*
Y238220D01*
Y228406D01*
X642758Y227758D01*
X639785D01*
X638015D01*
G37*
G36*
G01X641707Y261500D02*
G03I-707J0D01*
G37*
G36*
G01X659328Y230352D02*
X654680D01*
X654556Y230476D01*
Y238595D01*
X654713Y238752D01*
X659401D01*
X659661Y238492D01*
Y230685D01*
X659328Y230352D01*
G37*
G36*
G01X681868Y267817D02*
X684572D01*
X684755Y267634D01*
Y266619D01*
X679667Y261531D01*
X677147D01*
X668429Y252813D01*
Y222245D01*
X668224Y222040D01*
X662884D01*
X662724Y222200D01*
Y249898D01*
X665135Y252309D01*
Y253606D01*
Y264052D01*
X665655Y264572D01*
X678622D01*
X681868Y267817D01*
G37*
G36*
G01X698801Y250532D02*
X700523D01*
X700704Y250351D01*
Y246104D01*
X699700Y245100D01*
X698100D01*
Y238900D01*
X694919Y235719D01*
X672224D01*
X670929Y237014D01*
Y250358D01*
X671091Y250520D01*
X689091D01*
X689267Y250344D01*
Y247596D01*
X690670Y246193D01*
X697187D01*
X697419Y246425D01*
Y249378D01*
X698573Y250532D01*
X698801D01*
G37*
G36*
G01X684705Y270462D02*
X677146D01*
X674657Y267973D01*
X672720D01*
X671061D01*
X670710Y268324D01*
Y271291D01*
X669466Y272535D01*
Y275391D01*
X669561Y275486D01*
X672656D01*
X673070Y275072D01*
Y274000D01*
X675380Y271690D01*
X684706D01*
X684817Y271579D01*
Y270574D01*
X684705Y270462D01*
G37*
G36*
G01X659707Y284000D02*
G03I-707J0D01*
G37*
G36*
G01X703400Y293300D02*
X711984D01*
X712184Y293100D01*
Y290200D01*
X707884Y285900D01*
Y271000D01*
X704284Y267400D01*
Y260400D01*
X710226Y254458D01*
Y232815D01*
X709845Y232434D01*
X703583D01*
X703423Y232594D01*
Y236860D01*
X705100Y238537D01*
Y238900D01*
Y250300D01*
Y252716D01*
Y253209D01*
X702984Y255325D01*
Y267300D01*
X701884Y268400D01*
Y284800D01*
X702984Y285900D01*
Y292884D01*
X703400Y293300D01*
G37*
G36*
G01X687684Y325300D02*
X701484D01*
X701884Y324900D01*
Y318040D01*
X687484D01*
Y325100D01*
X687684Y325300D01*
G37*
G36*
G01X732541Y170559D02*
X719159Y183941D01*
G02X719100Y184083I141J142D01*
G01Y199417D01*
G02X719159Y199559I200J0D01*
G01X720041Y200441D01*
G02X720183Y200500I142J-141D01*
G01X758517D01*
G02X758659Y200441I0J-200D01*
G01X759916Y199184D01*
G02X759975Y199042I-141J-142D01*
G01Y183708D01*
G02X759916Y183566I-200J0D01*
G01X746909Y170559D01*
G02X746767Y170500I-142J141D01*
G01X732683D01*
G02X732541Y170559I0J200D01*
G37*
G36*
G01X712884Y276331D02*
X716205D01*
X717153D01*
X724984Y268500D01*
X732484D01*
X732853Y268869D01*
Y272036D01*
Y276267D01*
X732494Y276626D01*
X719612D01*
X718858D01*
X717885Y277599D01*
X716799D01*
X712822D01*
X712611Y277388D01*
Y276604D01*
X712884Y276331D01*
G37*
G36*
G01X732854Y287856D02*
Y283954D01*
X732400Y283500D01*
X726084D01*
X725218Y282634D01*
X718774D01*
X716394Y280254D01*
X712886D01*
X712632Y280508D01*
Y281375D01*
X712865Y281608D01*
X715895D01*
X722387Y288100D01*
X732610D01*
X732854Y287856D01*
G37*
G36*
G01X881207Y369500D02*
G03I-707J0D01*
G37*
G36*
G01X1165810Y263993D02*
X1166969D01*
X1169648Y261314D01*
X1189184D01*
X1196729Y253769D01*
Y184593D01*
X1195754Y183618D01*
X1178969D01*
X1175716Y180365D01*
Y131155D01*
X1177103Y129768D01*
X1196599D01*
X1196730Y129637D01*
Y57230D01*
X1196500Y57000D01*
X1107603D01*
X1100334Y64269D01*
Y105768D01*
X1091057Y115045D01*
X907614D01*
G02X907472Y115104I0J200D01*
G01X905559Y117017D01*
G02X905500Y117159I141J142D01*
G01Y184334D01*
G02X905559Y184476I200J0D01*
G01X906483Y185400D01*
X956700D01*
X979438Y162662D01*
X1078465D01*
X1086412Y170609D01*
Y196258D01*
X1089538Y199384D01*
X1161294D01*
X1165043Y203133D01*
Y242914D01*
X1168100Y245971D01*
Y258740D01*
X1165678Y261162D01*
Y263861D01*
X1165810Y263993D01*
G37*
G36*
G01X964700Y380000D02*
X1002417D01*
G02X1002559Y379941I0J-200D01*
G01X1013941Y368559D01*
G02X1014000Y368417I-141J-142D01*
G01Y246083D01*
G02X1013941Y245941I-200J0D01*
G01Y216639D01*
G02X1013882Y216497I-200J0D01*
G01X1012816Y215431D01*
G02X1012674Y215372I-142J141D01*
G01X906947D01*
G02X906805Y215431I0J200D01*
G01X905559Y216677D01*
G02X905500Y216819I141J142D01*
G01Y320800D01*
X964700Y380000D01*
G37*
G36*
G01X974461Y200520D02*
X1013026D01*
X1014500Y199046D01*
Y183828D01*
X1001172Y170500D01*
X986995D01*
X973488Y184007D01*
Y199547D01*
X974461Y200520D01*
G37*
G36*
G01X1029557Y263666D02*
X1037723D01*
X1039663D01*
X1046389Y270392D01*
X1049419D01*
X1049652Y270625D01*
Y271492D01*
X1049398Y271746D01*
X1045890D01*
X1043510Y269366D01*
X1029876D01*
X1029430Y268920D01*
Y268362D01*
Y263793D01*
X1029557Y263666D01*
G37*
G36*
G01X1028600Y283500D02*
X1037300D01*
X1045131Y275669D01*
X1049400D01*
X1049673Y275396D01*
Y274612D01*
X1049462Y274401D01*
X1044399D01*
X1043300Y275500D01*
X1028700D01*
X1028300Y275900D01*
Y283200D01*
X1028600Y283500D01*
G37*
G36*
G01X1052000Y303500D02*
X1058200D01*
X1058300Y303400D01*
Y293700D01*
X1059300Y292700D01*
Y284700D01*
X1060400Y283600D01*
Y267200D01*
X1059300Y266100D01*
Y259100D01*
X1058900Y258700D01*
X1050300D01*
X1050100Y258900D01*
Y261800D01*
X1054400Y266100D01*
Y281000D01*
X1058000Y284600D01*
Y291600D01*
X1053500Y296100D01*
X1033000D01*
X1032600Y296500D01*
Y301851D01*
X1033450Y302701D01*
X1051201D01*
X1052000Y303500D01*
G37*
G36*
G01X1036500Y342000D02*
X1090000D01*
X1091500Y340500D01*
Y333400D01*
X1091140Y333040D01*
X1042640D01*
X1039750Y330150D01*
Y311299D01*
X1033201D01*
X1033000Y311500D01*
Y338400D01*
X1036500Y341900D01*
Y342000D01*
G37*
G36*
G01X1060600Y234200D02*
X1074700D01*
X1074800Y234100D01*
Y226900D01*
X1074600Y226700D01*
X1060800D01*
X1060400Y227100D01*
Y234000D01*
X1060600Y234200D01*
G37*
G36*
G01X1153197Y313777D02*
X1156050D01*
X1156209Y313618D01*
Y308040D01*
X1155606Y307437D01*
Y301732D01*
X1155289Y301415D01*
X1153927D01*
X1153895Y301447D01*
X1150378Y297930D01*
Y291858D01*
X1151318Y290918D01*
Y286955D01*
X1151539Y286734D01*
X1158005D01*
X1159390Y285349D01*
Y265374D01*
X1159311Y265295D01*
X1153505D01*
X1153265Y265055D01*
Y259200D01*
X1155305Y257160D01*
X1156639D01*
X1158850Y254949D01*
Y243350D01*
X1158100Y242600D01*
Y232983D01*
X1156653Y231536D01*
X1110098D01*
X1091332Y212770D01*
X1055725D01*
X1054009Y214486D01*
Y247861D01*
X1058533D01*
X1060109Y246285D01*
Y245281D01*
X1057396Y242570D01*
Y225166D01*
X1059447Y223115D01*
X1077303D01*
X1078488Y224300D01*
Y243129D01*
X1077218Y244399D01*
X1072733D01*
X1072395Y244737D01*
Y249053D01*
X1072818Y249476D01*
X1081830D01*
X1092281Y239025D01*
X1102647D01*
X1104255Y240633D01*
Y249604D01*
X1103579Y250280D01*
X1096555D01*
X1096386Y250449D01*
Y252312D01*
X1096597Y252523D01*
X1103539D01*
X1104131Y253115D01*
Y275921D01*
X1103581Y276471D01*
X1095288D01*
X1095119Y276640D01*
Y279391D01*
X1095415Y279687D01*
X1099477D01*
X1099942Y280152D01*
Y285906D01*
X1100070Y286034D01*
X1109134D01*
X1109600Y286500D01*
Y292000D01*
X1109100Y292500D01*
X1098217D01*
X1098094Y292623D01*
Y298358D01*
X1098231Y298495D01*
X1107434D01*
X1110566Y301627D01*
X1121736D01*
X1122159Y301204D01*
Y295576D01*
X1119324Y292741D01*
Y285500D01*
X1118855Y285031D01*
G03X1118500Y285062I-356J-2031D01*
G03Y280938I0J-2062D01*
G03X1119000Y280999I2J2062D01*
G01X1119855D01*
X1121307Y279547D01*
X1124987D01*
X1125181Y279353D01*
Y277773D01*
X1124888Y277480D01*
X1121566D01*
X1121116Y277030D01*
Y269265D01*
X1121892Y268489D01*
X1125001D01*
X1125130Y268360D01*
Y261412D01*
X1124860Y261142D01*
X1121427D01*
X1120611Y260326D01*
Y252778D01*
X1117814Y249981D01*
Y245063D01*
X1118605Y244272D01*
Y242690D01*
X1122246Y239049D01*
X1152357D01*
X1153415Y240107D01*
Y242624D01*
X1156039Y245248D01*
Y254152D01*
X1151999Y258192D01*
Y265133D01*
X1151833Y265299D01*
X1144939D01*
X1144826Y265412D01*
Y286554D01*
X1145033Y286761D01*
X1147921D01*
X1148076Y286916D01*
Y299764D01*
X1153039Y304727D01*
Y313619D01*
X1153197Y313777D01*
G37*
G36*
G01X1065607Y285084D02*
X1076534D01*
X1076632Y284986D01*
Y263029D01*
X1076536Y262933D01*
X1066111D01*
X1065193Y262015D01*
Y258854D01*
Y257978D01*
X1062642Y255427D01*
Y244615D01*
X1062527Y244500D01*
X1060533D01*
X1054117D01*
X1054009Y244608D01*
Y249509D01*
X1063950Y259450D01*
Y262130D01*
X1065538Y263718D01*
Y285015D01*
X1065607Y285084D01*
G37*
G36*
G01X1059381Y316281D02*
X1090060D01*
X1091355Y314986D01*
Y301642D01*
X1091193Y301480D01*
X1073193D01*
X1073017Y301656D01*
Y304404D01*
X1071614Y305807D01*
X1065097D01*
X1063653Y304363D01*
Y301638D01*
X1063483Y301468D01*
X1061761D01*
X1061580Y301649D01*
Y304520D01*
X1055600Y310500D01*
X1052000D01*
Y315100D01*
X1058200D01*
X1059381Y316281D01*
G37*
G36*
G01X1102207Y268500D02*
G03I-707J0D01*
G37*
G36*
G01X1077579Y281538D02*
X1085138D01*
X1087627Y284027D01*
X1089564D01*
X1091223D01*
X1091574Y283676D01*
Y280709D01*
X1092818Y279465D01*
Y276609D01*
X1092723Y276514D01*
X1089628D01*
X1089214Y276928D01*
Y278000D01*
X1086904Y280310D01*
X1077578D01*
X1077467Y280421D01*
Y281426D01*
X1077579Y281538D01*
G37*
G36*
G01X1097080Y287879D02*
X1096629Y287428D01*
X1083662D01*
X1080416Y284183D01*
X1077712D01*
X1077529Y284366D01*
Y285381D01*
X1082617Y290469D01*
X1085137D01*
X1093211Y298543D01*
X1097000D01*
X1097080Y298463D01*
Y287879D01*
G37*
G36*
G01X1085329Y329960D02*
X1092127D01*
X1099068Y323019D01*
Y300843D01*
X1097149Y298924D01*
X1097102Y298877D01*
X1097097Y298872D01*
X1097080Y298855D01*
Y297331D01*
X1093271D01*
X1092635Y297967D01*
X1094519Y299851D01*
Y321197D01*
X1090795Y324921D01*
X1085971D01*
X1085210Y325682D01*
Y329841D01*
X1085329Y329960D01*
G37*
G36*
G01X1102157Y314713D02*
X1106553D01*
X1107767Y313499D01*
Y307363D01*
X1107245Y306841D01*
X1107018Y306614D01*
X1102593D01*
X1102132Y307075D01*
Y314688D01*
X1102157Y314713D01*
G37*
G36*
G01X1119207Y283000D02*
G03I-707J0D01*
G37*
G36*
G01X1129337Y324500D02*
X1129914Y323923D01*
Y309888D01*
X1129340Y309314D01*
X1119006D01*
X1118500Y309820D01*
Y323500D01*
X1119500Y324500D01*
X1129337D01*
G37*
G36*
G01X1157966Y290798D02*
Y291400D01*
X1159000Y292434D01*
Y303125D01*
Y303356D01*
X1156556Y305800D01*
Y307360D01*
X1156746Y307550D01*
X1156923D01*
X1162479Y313106D01*
X1164160Y314787D01*
X1168989D01*
X1169063Y314713D01*
Y309310D01*
X1169041Y309288D01*
X1164918D01*
X1164005D01*
X1163842D01*
X1161533Y306979D01*
Y306816D01*
Y305903D01*
Y293288D01*
X1159125Y290880D01*
Y287900D01*
X1159014Y287789D01*
X1158127D01*
X1157936Y287980D01*
Y290768D01*
X1157966Y290798D01*
G37*
G36*
G01X1136600Y324500D02*
X1143600D01*
X1144100Y324000D01*
Y318000D01*
X1143600Y317500D01*
X1136600D01*
X1136100Y318000D01*
Y324000D01*
X1136600Y324500D01*
G37*
G36*
G01X1171897Y291672D02*
X1167624Y287399D01*
Y286301D01*
X1167648Y286278D01*
X1172233D01*
X1177575Y291620D01*
Y316677D01*
X1176713Y317539D01*
X1172581D01*
X1172108Y317066D01*
Y291883D01*
X1171897Y291672D01*
G37*
G36*
G01X1164624Y298725D02*
X1165766Y297583D01*
Y288022D01*
X1165840Y287948D01*
X1166972D01*
X1167077Y288053D01*
Y292920D01*
X1169065Y294908D01*
Y305674D01*
X1169014Y305726D01*
X1164680D01*
X1164624Y305670D01*
Y298725D01*
G37*
G36*
G01X1187000Y398941D02*
X1350106D01*
G02X1350248Y398882I0J-200D01*
G01X1356018Y393112D01*
G02X1356077Y392970I-141J-142D01*
G01Y335277D01*
X1347200Y326400D01*
X1330900D01*
X1315516Y341784D01*
X1241571D01*
G03X1241429Y341725I0J-200D01*
G01X1232040Y332336D01*
X1188448D01*
X1185000Y335784D01*
Y396941D01*
X1187000Y398941D01*
G37*
G36*
G01X1226800Y181700D02*
X1274900D01*
X1276000Y180600D01*
Y59700D01*
X1272800Y56500D01*
X1228200D01*
X1225400Y59300D01*
Y180300D01*
X1226800Y181700D01*
G37*
G36*
G01Y314900D02*
X1274900D01*
X1276000Y313800D01*
Y185300D01*
X1274700Y184000D01*
X1225400D01*
Y313500D01*
X1226800Y314900D01*
G37*
G36*
G01X1566251Y666846D02*
X1577088D01*
G02X1577222Y666790I-5J-200D01*
G02X1577236Y666775I-139J-144D01*
G01X1577433Y666541D01*
G02X1577473Y666462I-154J-128D01*
G01X1577484Y666420D01*
X1577476Y666376D01*
G03X1577329Y664689I9631J-1689D01*
G01Y664685D01*
G03X1578123Y660827I9778J2D01*
G02Y660669I-184J-79D01*
G03X1577329Y656811I8984J-3860D01*
G03X1578123Y652953I9778J2D01*
G02Y652795I-184J-79D01*
G03X1577329Y648937I8984J-3860D01*
G03X1578123Y645079I9778J2D01*
G02Y644921I-184J-79D01*
G03X1577329Y641063I8984J-3860D01*
G03X1578123Y637205I9778J2D01*
G02Y637047I-184J-79D01*
G03X1577329Y633189I8984J-3860D01*
G03X1578123Y629331I9778J2D01*
G02Y629173I-184J-79D01*
G03X1577329Y625315I8984J-3860D01*
G03X1578123Y621457I9778J2D01*
G02Y621299I-184J-79D01*
G03X1577329Y617441I8984J-3860D01*
G03X1578123Y613583I9778J2D01*
G02Y613425I-184J-79D01*
G03X1577329Y609567I8984J-3860D01*
G03X1578123Y605709I9778J2D01*
G02Y605551I-184J-79D01*
G03X1577329Y601693I8984J-3860D01*
G01Y601691D01*
G03X1579456Y595603I9780J1D01*
G01X1579500Y595479D01*
Y588083D01*
G03X1579559Y587941I200J0D01*
G01X1583441Y584059D01*
G03X1583583Y584000I142J141D01*
G01X1629417D01*
G02X1629508Y583978I0J-200D01*
G02X1629558Y583942I-90J-178D01*
G01X1633883Y579617D01*
G02X1633919Y579567I-142J-140D01*
G02X1633941Y579476I-178J-91D01*
G01Y538642D01*
G03X1633976Y538530I200J1D01*
G01X1633986Y538512D01*
X1633993Y538488D01*
G02X1634000Y538436I-193J-52D01*
G01Y213083D01*
G02X1633978Y212992I-200J0D01*
G02X1633942Y212942I-178J90D01*
G01X1549000Y128000D01*
G02X1548978Y127981I-141J141D01*
G02X1548858Y127941I-120J160D01*
G01X1545161D01*
G02X1545041Y127981I0J200D01*
G02X1545019Y128000I119J160D01*
G01X1543902Y129117D01*
G03X1543760Y129176I-142J-141D01*
G01X1446839D01*
G03X1446697Y129117I0J-200D01*
G01X1395080Y77500D01*
X1294025D01*
X1293600Y77925D01*
Y91500D01*
X1293660Y91560D01*
G02X1293600Y91702I138J142D01*
G01Y95998D01*
G02X1293800Y96198I200J0D01*
G01X1333215D01*
G03X1333357Y96257I0J200D01*
G01X1336541Y99441D01*
G03X1336600Y99583I-141J142D01*
G01Y117917D01*
G03X1336541Y118059I-200J0D01*
G01X1333257Y121343D01*
G03X1333115Y121402I-142J-141D01*
G01X1294059D01*
X1293600Y121861D01*
Y135900D01*
X1293660Y135960D01*
G02X1293600Y136102I138J142D01*
G01Y140398D01*
G02X1293800Y140598I200J0D01*
G01X1351956D01*
X1353859Y142501D01*
Y150900D01*
X1357900D01*
X1360190Y153190D01*
G03X1363602Y160000I-5090J6810D01*
G03X1359330Y167375I-8502J0D01*
G03X1354800Y168701I-4530J-7075D01*
G01X1351527D01*
G03X1349358Y169520I-4525J-8702D01*
G03X1345300Y171155I-4059J-4220D01*
G03X1339548Y166394I0J-5855D01*
G03X1339373Y166167I5853J-4693D01*
G03X1339049Y165743I7629J-6165D01*
G01X1332857D01*
G03X1332715Y165802I-142J-141D01*
G01X1294059D01*
X1293600Y166261D01*
Y180300D01*
X1293660Y180360D01*
G02X1293600Y180502I138J142D01*
G01Y184798D01*
G02X1293800Y184998I200J0D01*
G01X1352029D01*
X1353862Y186831D01*
Y195408D01*
X1353870Y195400D01*
X1356600D01*
X1357462Y196262D01*
G03X1363502Y204400I-2462J8138D01*
G03X1355000Y212902I-8502J0D01*
G03X1354000Y212843I0J-8502D01*
G03X1353000Y212902I-1000J-8443D01*
G03X1352113Y212856I-4J-8502D01*
G03X1347002Y214281I-5112J-8456D01*
G01X1347000D01*
G03X1338959Y210143I0J-9882D01*
G01X1334457D01*
G03X1334315Y210202I-142J-141D01*
G01X1294059D01*
X1293600Y210661D01*
Y224700D01*
X1293660Y224760D01*
G02X1293600Y224902I138J142D01*
G01Y229198D01*
G02X1293800Y229398I200J0D01*
G01X1333415D01*
G03X1333557Y229457I0J200D01*
G01X1337041Y232941D01*
G03X1337100Y233083I-141J142D01*
G01Y251917D01*
G03X1337041Y252059I-200J0D01*
G01X1334557Y254543D01*
G03X1334415Y254602I-142J-141D01*
G01X1294059D01*
X1293600Y255061D01*
Y269100D01*
X1293660Y269160D01*
G02X1293600Y269302I138J142D01*
G01Y273598D01*
G02X1293800Y273798I200J0D01*
G01X1334315D01*
G03X1334457Y273857I0J200D01*
G01X1337041Y276441D01*
G03X1337100Y276583I-141J142D01*
G01Y296417D01*
G03X1337041Y296559I-200J0D01*
G01X1334659Y298941D01*
G03X1334517Y299000I-142J-141D01*
G01X1319017D01*
G03X1318846Y299002I-173J-7500D01*
G01X1294059D01*
X1293600Y299461D01*
Y313500D01*
X1294541Y314441D01*
G02X1294683Y314500I142J-141D01*
G01X1360017D01*
G03X1360158Y314558I0J200D01*
G01X1367500Y321900D01*
Y392817D01*
X1370100Y395417D01*
G02X1370113Y395488I200J0D01*
G01X1370118Y395501D01*
G02X1370158Y395558I181J-85D01*
G01X1373217Y398617D01*
X1373244Y398631D01*
G03X1383319Y406005I-18912J36409D01*
G03X1383322Y406009I-158J122D01*
G02X1383331Y406017I138J-146D01*
G03X1384381Y407106I-5571J6422D01*
G01X1384389Y407115D01*
G03X1384391Y407117I-140J142D01*
G03X1390739Y416126I-30060J27922D01*
G01X1390775Y416175D01*
X1399041Y424441D01*
G03X1399100Y424583I-141J142D01*
G01Y532041D01*
G02X1399140Y532161I200J0D01*
G02X1399159Y532183I160J-119D01*
G01X1400999Y534023D01*
G02X1401021Y534042I141J-141D01*
G02X1401141Y534082I120J-160D01*
G01X1429088D01*
G03X1429230Y534141I0J200D01*
G01X1443437Y548348D01*
G03X1443496Y548490I-141J142D01*
G01Y593071D01*
G03X1443437Y593213I-200J0D01*
G01X1427414Y609236D01*
G02X1427395Y609258I141J141D01*
G02X1427355Y609378I160J120D01*
G01Y626860D01*
G02X1427358Y626894I200J-1D01*
G01X1427367Y626931D01*
G03X1428823Y634897I-21855J8111D01*
G01Y634907D01*
G03X1428837Y635388I-8488J488D01*
G01Y635394D01*
G03X1428824Y635851I-8502J-13D01*
G01Y636300D01*
G02X1429024Y636500I200J0D01*
G01X1519154D01*
X1519328Y636397D01*
G03X1529490I5081J2697D01*
G01X1529664Y636500D01*
X1560417D01*
G03X1560559Y636559I0J200D01*
G01X1561941Y637941D01*
G03X1562000Y638083I-141J142D01*
G01Y664917D01*
G02X1562022Y665008I200J0D01*
G02X1562058Y665058I178J-90D01*
G01X1563787Y666787D01*
G02X1563809Y666806I141J-141D01*
G02X1563929Y666846I120J-160D01*
G01X1565407D01*
X1565411Y666845D01*
G03X1565829Y666835I412J8492D01*
G03X1566247Y666845I6J8502D01*
G01X1566251Y666846D01*
G37*
G36*
G01X1428447Y668790D02*
X1542860D01*
G02X1543002Y668731I0J-200D01*
G01X1544458Y667275D01*
G02X1544517Y667133I-141J-142D01*
G01Y646707D01*
G02X1544458Y646565I-200J0D01*
G01X1542749Y644856D01*
G02X1542607Y644797I-142J141D01*
G01X1525166D01*
X1525153Y644799D01*
G03X1523665I-744J-5705D01*
G01X1523652Y644797D01*
X1428543D01*
G02X1428401Y644856I0J200D01*
G01X1426504Y646753D01*
G02X1426445Y646895I141J142D01*
G01Y666788D01*
G02X1426504Y666930I200J0D01*
G01X1428305Y668731D01*
G02X1428447Y668790I142J-141D01*
G37*
G36*
G01X1638100Y105300D02*
X1650900D01*
X1651800Y104400D01*
Y100500D01*
X1659820Y92480D01*
Y38000D01*
X1659827D01*
G03X1659820Y37410I25212J-594D01*
G01Y12720D01*
X1655100Y8000D01*
X1648672D01*
X1648668Y8001D01*
G03X1648460Y8005I-200J-4998D01*
G03X1648252Y8001I-8J-5002D01*
G01X1648248Y8000D01*
X1628672D01*
X1628668Y8001D01*
G03X1628460Y8005I-200J-4998D01*
G03X1628252Y8001I-8J-5002D01*
G01X1628248Y8000D01*
X1608672D01*
X1608668Y8001D01*
G03X1608460Y8005I-200J-4998D01*
G03X1608252Y8001I-8J-5002D01*
G01X1608248Y8000D01*
X1588672D01*
X1588668Y8001D01*
G03X1588460Y8005I-200J-4998D01*
G03X1588252Y8001I-8J-5002D01*
G01X1588248Y8000D01*
X1568672D01*
X1568668Y8001D01*
G03X1568460Y8005I-200J-4998D01*
G03X1568252Y8001I-8J-5002D01*
G01X1568248Y8000D01*
X1548672D01*
X1548668Y8001D01*
G03X1548460Y8005I-200J-4998D01*
G03X1548252Y8001I-8J-5002D01*
G01X1548248Y8000D01*
X1528672D01*
X1528668Y8001D01*
G03X1528460Y8005I-200J-4998D01*
G03X1528252Y8001I-8J-5002D01*
G01X1528248Y8000D01*
X1508672D01*
X1508668Y8001D01*
G03X1508460Y8005I-200J-4998D01*
G03X1508252Y8001I-8J-5002D01*
G01X1508248Y8000D01*
X1498341D01*
G02X1498183Y8078I1J200D01*
G01X1497961Y8366D01*
X1497942Y8455D01*
X1497954Y8501D01*
G03X1486731Y15059I-6537J1696D01*
G01X1486694Y15024D01*
X1486598Y14997D01*
X1486172Y15093D01*
X1486097Y15159D01*
X1486079Y15207D01*
G03X1484464Y17617I-5882J-2195D01*
G01X1484433Y17645D01*
X1484400Y17719D01*
X1484394Y18048D01*
G02X1484453Y18194I200J4D01*
G01X1496199Y29940D01*
G02X1496340Y29998I141J-142D01*
G01X1602198D01*
X1634678Y62478D01*
G03X1634737Y62620I-141J142D01*
G01Y101937D01*
X1638100Y105300D01*
G37*
G36*
G01X1586276Y667000D02*
X1601017D01*
G02X1601050Y666997I-2J-200D01*
G02X1601157Y666943I-32J-197D01*
G01X1604141Y663959D01*
G02X1604200Y663817I-141J-142D01*
G01Y633483D01*
G03X1604259Y633341I200J0D01*
G01X1620541Y617059D01*
G03X1620683Y617000I142J141D01*
G01X1715917D01*
G02X1716059Y616941I0J-200D01*
G01X1726841Y606159D01*
G02X1726900Y606017I-141J-142D01*
G01Y526683D01*
G03X1726959Y526541I200J0D01*
G01X1741941Y511559D01*
G03X1742083Y511500I142J141D01*
G01X1859917D01*
G02X1860059Y511441I0J-200D01*
G01X1866941Y504559D01*
G02X1867000Y504417I-141J-142D01*
G01Y443517D01*
G02X1866999Y443493I-200J-4D01*
G01X1866994Y443455D01*
G02X1866937Y443337I-199J23D01*
G01X1863159Y439559D01*
X1863131Y439530D01*
X1863057Y439500D01*
X1835922D01*
G03X1835780Y439441I0J-200D01*
G01X1826896Y430557D01*
G03X1826837Y430415I141J-142D01*
G01Y363750D01*
G02X1826836Y363726I-200J-4D01*
G01X1826831Y363688D01*
G02X1826774Y363570I-199J23D01*
G01X1824278Y361074D01*
X1824250Y361045D01*
X1824176Y361015D01*
X1777228D01*
G03X1777086Y360956I0J-200D01*
G01X1776534Y360404D01*
G02X1776479Y360365I-142J141D01*
G01X1776402Y360328D01*
X1776374Y360323D01*
G03X1775652Y359949I227J-1322D01*
G01X1767167Y351464D01*
X1767149Y351450D01*
X1767094Y351414D01*
X1767073Y351406D01*
G03X1766098Y350000I526J-1406D01*
G03X1767600Y348498I1502J0D01*
G03X1769003Y349465I0J1501D01*
G01X1769005Y349471D01*
X1769015Y349496D01*
X1769046Y349544D01*
X1769059Y349562D01*
X1771711Y352214D01*
G02X1771865Y352272I141J-142D01*
G01X1771896Y352270D01*
X1772236Y352142D01*
X1772259Y352124D01*
X1772284Y352105D01*
X1772376Y351980D01*
X1772395Y351930D01*
X1772397Y351901D01*
G03X1776027Y347490I4986J404D01*
G01X1776057Y347482D01*
X1776161Y347414D01*
X1776182Y347386D01*
G03X1777383Y346786I1201J902D01*
G03X1777932Y346891I-3J1502D01*
G01X1777978Y346910D01*
X1778077Y346899D01*
X1778393Y346684D01*
G02X1778480Y346518I-113J-165D01*
G01Y267997D01*
G02X1778479Y267973I-200J-4D01*
G01X1778474Y267935D01*
G02X1778417Y267817I-199J23D01*
G01X1777659Y267059D01*
X1777631Y267030D01*
X1777557Y267000D01*
X1739165D01*
G03X1739089Y266985I0J-200D01*
G01X1739053Y266970D01*
X1739026Y266943D01*
G03X1739024Y266941I140J-142D01*
G01X1735760Y263677D01*
G03X1735702Y263536I142J-141D01*
G01Y247062D01*
G03X1735761Y246920I200J0D01*
G01X1738122Y244559D01*
G03X1738264Y244500I142J141D01*
G01X1794017D01*
G02X1794159Y244441I0J-200D01*
G01X1795071Y243529D01*
G02X1795130Y243387I-141J-142D01*
G01Y214847D01*
G02X1795129Y214823I-200J-4D01*
G01X1795124Y214785D01*
G02X1795067Y214667I-199J23D01*
G01X1788259Y207859D01*
X1788231Y207830D01*
X1788157Y207800D01*
X1721383D01*
G03X1721241Y207741I0J-200D01*
G01X1712559Y199059D01*
G03X1712500Y198917I141J-142D01*
G01Y185579D01*
G02X1712441Y185437I-200J0D01*
G01X1709504Y182500D01*
X1705500D01*
X1699000Y189000D01*
X1681500D01*
X1679500Y187000D01*
X1638500D01*
X1620000Y168500D01*
Y152000D01*
X1621341Y150659D01*
G03X1621483Y150600I142J141D01*
G01X1627617D01*
G02X1627759Y150541I0J-200D01*
G01X1627941Y150359D01*
G02X1628000Y150217I-141J-142D01*
G01Y148783D01*
G02X1627941Y148641I-200J0D01*
G01X1627859Y148559D01*
G02X1627717Y148500I-142J141D01*
G01X1622283D01*
G03X1622141Y148441I0J-200D01*
G01X1621659Y147959D01*
G03X1621600Y147817I141J-142D01*
G01Y140700D01*
X1622300Y140000D01*
X1627717D01*
G02X1627859Y139941I0J-200D01*
G01X1627941Y139859D01*
G02X1628000Y139717I-141J-142D01*
G01Y110100D01*
X1631737Y106363D01*
Y93737D01*
X1627800Y89800D01*
Y66683D01*
G02X1627741Y66541I-200J0D01*
G01X1595259Y34059D01*
G02X1595117Y34000I-142J141D01*
G01X1496583D01*
G02X1496441Y34059I0J200D01*
G01X1494758Y35742D01*
X1494729Y35770D01*
X1494699Y35844D01*
Y43218D01*
G02X1494756Y43358I200J0D01*
G01X1501623Y50225D01*
G03X1502016Y51174I-949J949D01*
G01Y60435D01*
G02X1502075Y60577I200J0D01*
G01X1504110Y62612D01*
G02X1504285Y62668I142J-141D01*
G01X1504332Y62660D01*
X1504352Y62652D01*
G03X1505098Y62507I746J1848D01*
G01X1505100D01*
G03Y66493I0J1993D01*
G03X1503564Y65768I2J-1993D01*
G01X1503562Y65766D01*
X1503551Y65753D01*
X1503549Y65751D01*
X1503542Y65743D01*
X1503480Y65690D01*
X1503461Y65680D01*
G03X1503151Y65449I638J-1180D01*
G01X1500863Y63160D01*
G02X1500522Y63302I-141J142D01*
G01Y63500D01*
G03X1495838I-2342J0D01*
G01Y60799D01*
G02X1495730Y60622I-200J1D01*
G01X1495699Y60606D01*
X1495639Y60586D01*
G02X1495495Y60594I-62J190D01*
G01X1495464Y60608D01*
X1495440Y60625D01*
G02X1495377Y60694I112J166D01*
G01X1495364Y60718D01*
X1495342Y60782D01*
Y65007D01*
G02X1495446Y65182I200J0D01*
G03X1496230Y66500I-716J1318D01*
G03X1494728Y68002I-1502J0D01*
G03X1493316Y67012I0J-1502D01*
G01X1493301Y66970D01*
X1493051Y66721D01*
G03X1492856Y66473I950J-948D01*
G01X1492843Y66452D01*
X1492826Y66435D01*
G02X1492709Y66378I-141J142D01*
G01X1492397Y66339D01*
X1492395D01*
X1492353Y66333D01*
X1492265Y66362D01*
X1492055Y66572D01*
X1492025Y66635D01*
X1492022Y66670D01*
G03X1490228Y68302I-1794J-170D01*
G03X1488426Y66500I0J-1802D01*
G03X1489985Y64714I1803J0D01*
G01X1490060Y64704D01*
X1490158Y64591D01*
Y53165D01*
G02X1490157Y53142I-200J-3D01*
G01X1490153Y53113D01*
G02X1490096Y52994I-199J22D01*
G01X1465991Y28889D01*
G03X1465598Y27940I949J-949D01*
G01Y21216D01*
G02X1465597Y21193I-200J-3D01*
G01X1465593Y21164D01*
G02X1465536Y21045I-199J22D01*
G01X1465340Y20849D01*
X1465312Y20820D01*
X1465238Y20790D01*
X1465197D01*
G03X1464465Y20691I3J-2778D01*
G01X1464420Y20679D01*
X1464328Y20696D01*
X1464037Y20918D01*
X1464036Y20919D01*
X1464004Y20942D01*
X1463981Y20986D01*
X1463970Y21008D01*
X1463958Y21055D01*
Y27371D01*
G03X1463899Y27513I-200J0D01*
G01X1456578Y34834D01*
G03X1456436Y34893I-142J-141D01*
G01X1427829D01*
G02X1427805Y34894I-4J200D01*
G01X1427767Y34899D01*
G02X1427649Y34956I23J199D01*
G01X1426324Y36281D01*
G03X1426182Y36340I-142J-141D01*
G01X874074D01*
G02X873874Y36540I0J200D01*
G01Y101301D01*
G02X874074Y101501I200J0D01*
G01X929257D01*
G03X929285Y101504I-7J199D01*
G01X929315Y101508D01*
X929376Y101500D01*
X929413Y101484D01*
G02X929514Y101381I-83J-182D01*
G02X929517Y101372I-188J-68D01*
G01X929639Y101043D01*
X929651Y101012D01*
X929653Y100980D01*
G02X929627Y100869I-200J-12D01*
G01X929604Y100828D01*
G02X929572Y100787I-172J102D01*
G01X929539Y100754D01*
G03X923943Y88484I10658J-12272D01*
G03X956451I16254J0D01*
G03X950836Y100772I-16253J0D01*
G01X950835Y100773D01*
X950818Y100788D01*
X950793Y100821D01*
X950762Y100886D01*
G02X950742Y100972I180J87D01*
G01X950743Y101008D01*
X950877Y101371D01*
G02X951064Y101501I187J-70D01*
G01X1087450D01*
G02X1087590Y101444I0J-200D01*
G01X1088108Y100926D01*
G02X1088167Y100784I-141J-142D01*
G01Y53516D01*
G03X1088226Y53374I200J0D01*
G01X1096541Y45059D01*
G03X1096683Y45000I142J141D01*
G01X1191117D01*
G02X1191257Y44943I0J-200D01*
G01X1193932Y42268D01*
G03X1194074Y42209I142J141D01*
G01X1272674D01*
G03X1272816Y42268I0J200D01*
G01X1289589Y59041D01*
G02X1289731Y59100I142J-141D01*
G01X1324017D01*
G03X1324159Y59159I0J200D01*
G01X1325422Y60422D01*
X1397918D01*
X1406037Y68541D01*
G03X1406179Y68600I0J200D01*
G01X1454961Y117382D01*
G02X1455103Y117441I142J-141D01*
G01X1517359D01*
G03X1517435Y117456I0J200D01*
G01X1517505Y117485D01*
G02X1517581Y117500I76J-185D01*
G01X1517679D01*
G02X1517859Y117387I0J-200D01*
G01X1518009Y117077D01*
G02X1518025Y116950I-180J-87D01*
G01X1518021Y116932D01*
X1517991Y116848D01*
X1517970Y116822D01*
G03X1516098Y111500I6629J-5322D01*
G03X1533102I8502J0D01*
G03X1531209Y116848I-8501J0D01*
G01X1531172Y116893D01*
X1531159Y117008D01*
X1531340Y117386D01*
G02X1531520Y117500I181J-86D01*
G01X1556917D01*
G03X1557059Y117559I0J200D01*
G01X1646941Y207441D01*
G03X1647000Y207583I-141J142D01*
G01Y587917D01*
G03X1646941Y588059I-200J0D01*
G01X1636059Y598941D01*
G03X1635917Y599000I-142J-141D01*
G01X1586325D01*
G02X1586222Y599029I1J200D01*
G01X1586163Y599065D01*
X1586140Y599079D01*
X1586066Y599156D01*
X1586053Y599180D01*
G03X1585917Y599420I-6767J-3676D01*
G01X1585915Y599422D01*
X1585902Y599444D01*
G03X1585889Y599467I-6711J-3778D01*
G01X1585881Y599480D01*
X1585866Y599518D01*
G02X1585862Y599529I186J74D01*
G01X1585841Y599591D01*
X1585844Y599631D01*
X1585846Y599661D01*
X1585849Y599675D01*
G03X1586059Y601691I-9569J2016D01*
G01Y601696D01*
G03X1585603Y604646I-9779J-1D01*
G01X1585598Y604661D01*
X1585588Y604726D01*
X1585591Y604753D01*
G03X1585589Y606519I-7652J874D01*
G02X1585597Y606603I199J23D01*
G03X1586058Y609567I-9317J2967D01*
G03X1585597Y612531I-9778J-3D01*
G02X1585589Y612615I191J61D01*
G03Y614393I-7650J889D01*
G02X1585597Y614477I199J23D01*
G03X1586058Y617441I-9317J2967D01*
G03X1585597Y620405I-9778J-3D01*
G02X1585589Y620489I191J61D01*
G03Y622267I-7650J889D01*
G02X1585597Y622351I199J23D01*
G03X1586058Y625315I-9317J2967D01*
G03X1585597Y628279I-9778J-3D01*
G02X1585589Y628363I191J61D01*
G03Y630141I-7650J889D01*
G02X1585597Y630225I199J23D01*
G03X1586058Y633189I-9317J2967D01*
G03X1585597Y636153I-9778J-3D01*
G02X1585589Y636237I191J61D01*
G03Y638015I-7650J889D01*
G02X1585597Y638099I199J23D01*
G03X1586058Y641063I-9317J2967D01*
G03X1585597Y644027I-9778J-3D01*
G02X1585589Y644111I191J61D01*
G03Y645889I-7650J889D01*
G02X1585597Y645973I199J23D01*
G03X1586058Y648937I-9317J2967D01*
G03X1585597Y651901I-9778J-3D01*
G02X1585589Y651985I191J61D01*
G03Y653763I-7650J889D01*
G02X1585597Y653847I199J23D01*
G03X1586058Y656811I-9317J2967D01*
G03X1585597Y659775I-9778J-3D01*
G02X1585589Y659859I191J61D01*
G03Y661637I-7650J889D01*
G02X1585597Y661721I199J23D01*
G03X1586058Y664685I-9317J2967D01*
G03X1585887Y666502I-9778J-4D01*
G01X1585884Y666515D01*
X1585875Y666564D01*
X1585895Y666647D01*
X1585920Y666680D01*
X1585923Y666685D01*
X1586122Y666927D01*
G02X1586276Y667000I155J-127D01*
G37*
G36*
G01X1701807Y178500D02*
G03I-707J0D01*
G37*
G36*
G01X1712707Y153000D02*
G03I-707J0D01*
G37*
G36*
G01X1791600Y256500D02*
Y247500D01*
X1790100Y246000D01*
X1739392D01*
X1738041Y247351D01*
Y261638D01*
X1739903Y263500D01*
X1789600D01*
X1791600Y261500D01*
Y256500D01*
G37*
G36*
G01X1764707Y107000D02*
G03I-707J0D01*
G37*
G36*
G01X1764207Y113000D02*
G03I-707J0D01*
G37*
G36*
G01X1774207Y121000D02*
G03I-707J0D01*
G37*
G36*
G01X1845207Y416500D02*
G03I-707J0D01*
G37*
G36*
G01X1848207Y437000D02*
G03I-707J0D01*
G37*
%LPC*%
G75*
G36*
G01X162784Y233502D02*
G02X163285Y234002I501J-1D01*
G01X170285D01*
G02X170786Y233500I-1J-502D01*
G01Y226498D01*
G02X170285Y225998I-501J1D01*
G01X163285D01*
G02X162784Y226500I1J502D01*
G01Y233502D01*
G37*
G36*
G01X239784D02*
G02X240285Y234002I501J-1D01*
G01X247285D01*
G02X247786Y233500I-1J-502D01*
G01Y226498D01*
G02X247285Y225998I-501J1D01*
G01X240285D01*
G02X239784Y226500I1J502D01*
G01Y233502D01*
G37*
G36*
G01X162784Y313502D02*
G02X163285Y314002I501J-1D01*
G01X170285D01*
G02X170786Y313500I-1J-502D01*
G01Y306498D01*
G02X170285Y305998I-501J1D01*
G01X163285D01*
G02X162784Y306500I1J502D01*
G01Y313502D01*
G37*
G36*
G01X239784D02*
G02X240285Y314002I501J-1D01*
G01X247285D01*
G02X247786Y313500I-1J-502D01*
G01Y306498D01*
G02X247285Y305998I-501J1D01*
G01X240285D01*
G02X239784Y306500I1J502D01*
G01Y313502D01*
G37*
G36*
G01X162784Y393502D02*
G02X163285Y394002I501J-1D01*
G01X170285D01*
G02X170786Y393500I-1J-502D01*
G01Y386498D01*
G02X170285Y385998I-501J1D01*
G01X163285D01*
G02X162784Y386500I1J502D01*
G01Y393502D01*
G37*
G36*
G01X239784D02*
G02X240285Y394002I501J-1D01*
G01X247285D01*
G02X247786Y393500I-1J-502D01*
G01Y386498D01*
G02X247285Y385998I-501J1D01*
G01X240285D01*
G02X239784Y386500I1J502D01*
G01Y393502D01*
G37*
G36*
G01X162784Y473502D02*
G02X163285Y474002I501J-1D01*
G01X170285D01*
G02X170786Y473500I-1J-502D01*
G01Y466498D01*
G02X170285Y465998I-501J1D01*
G01X163285D01*
G02X162784Y466500I1J502D01*
G01Y473502D01*
G37*
G36*
G01X239784D02*
G02X240285Y474002I501J-1D01*
G01X247285D01*
G02X247786Y473500I-1J-502D01*
G01Y466498D01*
G02X247285Y465998I-501J1D01*
G01X240285D01*
G02X239784Y466500I1J502D01*
G01Y473502D01*
G37*
G36*
G01X162784Y553502D02*
G02X163285Y554002I501J-1D01*
G01X170285D01*
G02X170786Y553500I-1J-502D01*
G01Y546498D01*
G02X170285Y545998I-501J1D01*
G01X163285D01*
G02X162784Y546500I1J502D01*
G01Y553502D01*
G37*
G36*
G01X239784D02*
G02X240285Y554002I501J-1D01*
G01X247285D01*
G02X247786Y553500I-1J-502D01*
G01Y546498D01*
G02X247285Y545998I-501J1D01*
G01X240285D01*
G02X239784Y546500I1J502D01*
G01Y553502D01*
G37*
G36*
G01X655997Y330075D02*
G02X659003I1503J0D01*
G02X658344Y328831I-1504J0D01*
G03Y328169I224J-331D01*
G02X659003Y326925I-845J-1244D01*
G02X655997I-1503J0D01*
G02X656656Y328169I1504J0D01*
G03Y328831I-224J331D01*
G02X655997Y330075I845J1244D01*
G37*
G36*
G01X1484498Y233500D02*
G02X1485000Y234002I502J0D01*
G01X1492000D01*
G02X1492502Y233500I0J-502D01*
G01Y226500D01*
G02X1492000Y225998I-502J0D01*
G01X1485000D01*
G02X1484498Y226500I0J502D01*
G01Y233500D01*
G37*
G36*
G01X1561498D02*
G02X1562000Y234002I502J0D01*
G01X1569000D01*
G02X1569502Y233500I0J-502D01*
G01Y226500D01*
G02X1569000Y225998I-502J0D01*
G01X1562000D01*
G02X1561498Y226500I0J502D01*
G01Y233500D01*
G37*
G36*
G01X1484498Y313500D02*
G02X1485000Y314002I502J0D01*
G01X1492000D01*
G02X1492502Y313500I0J-502D01*
G01Y306500D01*
G02X1492000Y305998I-502J0D01*
G01X1485000D01*
G02X1484498Y306500I0J502D01*
G01Y313500D01*
G37*
G36*
G01X1561498D02*
G02X1562000Y314002I502J0D01*
G01X1569000D01*
G02X1569502Y313500I0J-502D01*
G01Y306500D01*
G02X1569000Y305998I-502J0D01*
G01X1562000D01*
G02X1561498Y306500I0J502D01*
G01Y313500D01*
G37*
G36*
G01X1484498Y393500D02*
G02X1485000Y394002I502J0D01*
G01X1492000D01*
G02X1492502Y393500I0J-502D01*
G01Y386500D01*
G02X1492000Y385998I-502J0D01*
G01X1485000D01*
G02X1484498Y386500I0J502D01*
G01Y393500D01*
G37*
G36*
G01X1561498D02*
G02X1562000Y394002I502J0D01*
G01X1569000D01*
G02X1569502Y393500I0J-502D01*
G01Y386500D01*
G02X1569000Y385998I-502J0D01*
G01X1562000D01*
G02X1561498Y386500I0J502D01*
G01Y393500D01*
G37*
G36*
G01X1484498Y473500D02*
G02X1485000Y474002I502J0D01*
G01X1492000D01*
G02X1492502Y473500I0J-502D01*
G01Y466500D01*
G02X1492000Y465998I-502J0D01*
G01X1485000D01*
G02X1484498Y466500I0J502D01*
G01Y473500D01*
G37*
G36*
G01X1561498D02*
G02X1562000Y474002I502J0D01*
G01X1569000D01*
G02X1569502Y473500I0J-502D01*
G01Y466500D01*
G02X1569000Y465998I-502J0D01*
G01X1562000D01*
G02X1561498Y466500I0J502D01*
G01Y473500D01*
G37*
G36*
G01X1484498Y553500D02*
G02X1485000Y554002I502J0D01*
G01X1492000D01*
G02X1492502Y553500I0J-502D01*
G01Y546500D01*
G02X1492000Y545998I-502J0D01*
G01X1485000D01*
G02X1484498Y546500I0J502D01*
G01Y553500D01*
G37*
G36*
G01X1561498D02*
G02X1562000Y554002I502J0D01*
G01X1569000D01*
G02X1569502Y553500I0J-502D01*
G01Y546500D01*
G02X1569000Y545998I-502J0D01*
G01X1562000D01*
G02X1561498Y546500I0J502D01*
G01Y553500D01*
G37*
G36*
G01X1658201Y193400D02*
G02X1658198Y193500I1799J104D01*
G02X1660000Y191698I1802J0D01*
G02X1659508Y191767I2J1802D01*
G01X1659464Y191779D01*
X1659375Y191764D01*
X1659046Y191531D01*
X1659002Y191452D01*
X1658999Y191407D01*
G02X1657500Y189998I-1499J93D01*
G02X1656042Y191141I0J1501D01*
G01X1656028Y191196D01*
X1655949Y191274D01*
X1655496Y191385D01*
X1655390Y191352D01*
X1655353Y191310D01*
G02X1654000Y190698I-1353J1190D01*
G02Y194302I0J1802D01*
G02X1655778Y192796I0J-1803D01*
G01X1655787Y192741D01*
X1655859Y192656D01*
X1656303Y192511D01*
X1656411Y192536D01*
X1656451Y192575D01*
G02X1657500Y193002I1049J-1075D01*
G02X1657738Y192983I0J-1502D01*
G01X1657783Y192976D01*
X1657870Y193001D01*
X1658169Y193271D01*
X1658203Y193354D01*
X1658201Y193400D01*
G37*
G36*
G01X1662290Y201929D02*
G02X1662197Y202500I1710J572D01*
G02X1665803I1803J0D01*
G02X1665710Y201929I-1803J1D01*
G01X1665688Y201870D01*
G02X1662312I-1688J630D01*
G01X1662290Y201929D01*
G37*
G36*
G01X1782737Y394390D02*
G03X1782833I48J194D01*
G02X1784035Y394537I1204J-4855D01*
G02X1789037Y389535I0J-5002D01*
G02X1788878Y388285I-5002J1D01*
G03Y388185I194J-50D01*
G02X1789037Y386935I-4843J-1251D01*
G02X1784035Y381933I-5002J0D01*
G02X1782833Y382080I2J5002D01*
G03X1782737I-48J-194D01*
G02X1781535Y381933I-1204J4855D01*
G01X1781534D01*
G02X1780287Y382091I0J5002D01*
G03X1780183Y382090I-50J-194D01*
G02X1778839Y381906I-1344J4819D01*
G01X1778838D01*
G02X1773836Y386908I0J5002D01*
G02X1773995Y388158I5002J-1D01*
G03Y388258I-194J50D01*
G02X1773836Y389508I4843J1251D01*
G02X1778838Y394510I5002J0D01*
G01X1778839D01*
G02X1780086Y394352I0J-5002D01*
G03X1780190Y394353I50J194D01*
G02X1781534Y394537I1344J-4819D01*
G01X1781535D01*
G02X1782737Y394390I-2J-5002D01*
G37*
G36*
G01Y410390D02*
G03X1782833I48J194D01*
G02X1784035Y410537I1204J-4855D01*
G02X1789037Y405535I0J-5002D01*
G02X1788878Y404285I-5002J1D01*
G03Y404185I194J-50D01*
G02X1789037Y402935I-4843J-1251D01*
G02X1784035Y397933I-5002J0D01*
G02X1782833Y398080I2J5002D01*
G03X1782737I-48J-194D01*
G02X1781535Y397933I-1204J4855D01*
G01X1781534D01*
G02X1780287Y398091I0J5002D01*
G03X1780183Y398090I-50J-194D01*
G02X1778839Y397906I-1344J4819D01*
G01X1778838D01*
G02X1773836Y402908I0J5002D01*
G02X1773995Y404158I5002J-1D01*
G03Y404258I-194J50D01*
G02X1773836Y405508I4843J1251D01*
G02X1778838Y410510I5002J0D01*
G01X1778839D01*
G02X1780086Y410352I0J-5002D01*
G03X1780190Y410353I50J194D01*
G02X1781534Y410537I1344J-4819D01*
G01X1781535D01*
G02X1782737Y410390I-2J-5002D01*
G37*
G54D82*
X325100Y64000D03*
X317000Y64500D03*
Y74475D03*
X321500D03*
X326000Y74476D03*
X330500D03*
X176785Y102000D03*
X187600Y106500D03*
X1503728Y74477D03*
X1494728Y83500D03*
X1527100Y98925D03*
X1622295Y114940D03*
Y118940D03*
X1614100Y125000D03*
X1706600Y186500D03*
X1667600Y198500D03*
X1661500Y199000D03*
G54D88*
X658925Y320000D03*
X662075D03*
X649059Y314000D03*
X649200Y254500D03*
X1112000Y296000D03*
X1618100Y148925D03*
X1704600Y201500D03*
G54D81*
X317000Y58000D03*
X332500Y63300D03*
X321500Y66500D03*
X156785Y101285D03*
X211425Y106075D03*
X210925Y115575D03*
X1499228Y74500D03*
X1490000Y80500D03*
X1551000Y96500D03*
X1597100Y126000D03*
Y145000D03*
X1769300Y329400D03*
X1769692Y334649D03*
X1769300Y340600D03*
X1767700Y346200D03*
G54D93*
X1625370Y103940D03*
G54D90*
X978600Y310955D03*
G54D86*
X166785Y200472D03*
X243785D03*
X166785Y280472D03*
X243785D03*
X166785Y360472D03*
X243785D03*
X166785Y440472D03*
X243785D03*
X166785Y520472D03*
X243785D03*
X1488500Y200472D03*
X1565500D03*
X1488500Y280472D03*
X1565500D03*
X1488500Y360472D03*
X1565500D03*
X1488500Y440472D03*
X1565500D03*
X1488500Y520472D03*
X1565500D03*
G54D91*
X1468504Y628465D03*
G54D89*
X940197Y313484D03*
G54D87*
X287402Y628465D03*
X263780Y659961D03*
X1444882D03*
G54D85*
X102422Y604336D03*
X1717750Y599624D03*
G54D92*
X1567500Y67000D03*
G54D83*
X231600Y81000D03*
X1529100Y78500D03*
G54D84*
X59055Y236614D03*
Y411594D03*
X1673228Y236614D03*
Y411614D03*
%LPD*%
G75*
G36*
G01X324707Y77000D02*
G03I-707J0D01*
G37*
G36*
G01X321707Y63000D02*
G03I-707J0D01*
G37*
G36*
G01X1490707Y84000D02*
G03I-707J0D01*
G37*
G54D10*
X19685Y-774040D03*
Y766166D03*
X231600Y81000D03*
X566575Y463701D03*
D03*
D03*
X1212478Y300181D03*
X1529100Y78500D03*
X1854331Y-774040D03*
Y766166D03*
G54D20*
X137303Y664685D03*
X223622Y617441D03*
X274646Y8012D03*
X303150Y617441D03*
X1465197Y8012D03*
X1484252Y617441D03*
X1540157D03*
X1568406Y664685D03*
G54D11*
G01X415200Y224500D02*
X408100D01*
G01X428100Y170300D02*
X430825Y173025D01*
X434100D01*
G01X417000Y164900D02*
X417500Y165400D01*
Y169600D01*
G01X434100Y173025D02*
Y169052D01*
X432104Y167056D01*
X428277D01*
G01X428100Y178900D02*
X424300D01*
X423100Y180100D01*
X421000D01*
G01X422000Y174815D02*
X421000Y175815D01*
Y180100D01*
G01X412000Y175000D02*
X412400Y174600D01*
Y169500D01*
G01X417500Y175400D02*
X417100Y175000D01*
X412000D01*
G01X438100Y173025D02*
Y170000D01*
G01X417500Y208900D02*
X417600Y209000D01*
Y213500D01*
G01X421000Y180100D02*
Y181500D01*
X417300Y185200D01*
G01X428100Y223300D02*
X424300D01*
X423100Y224500D01*
X421000D01*
G01D02*
Y227100D01*
X418500Y229600D01*
G01X422000Y219059D02*
X421578Y219481D01*
Y223922D01*
X421000Y224500D01*
G01X412400Y214000D02*
Y218900D01*
X412000Y219300D01*
G01D02*
X417400D01*
X417500Y219400D01*
G01X434100Y217425D02*
X430825D01*
X428100Y214700D01*
G01X430608Y211389D02*
X434100Y214881D01*
Y217425D01*
G01X420675Y213100D02*
X418000D01*
X417600Y213500D01*
G01X427825Y214425D02*
X428100Y214700D01*
G01X438100Y217425D02*
Y214500D01*
G01X565091Y302592D02*
X560034Y297535D01*
Y287112D01*
X572814Y274332D01*
X579235D01*
X581562Y272005D01*
G01X570443Y302702D02*
Y301398D01*
X564066Y295021D01*
Y287889D01*
X573870Y278085D01*
X577808D01*
G01X1201037Y318912D02*
Y312263D01*
X1184842Y296068D01*
Y288678D01*
X1182409Y286245D01*
G01D02*
X1179977Y283813D01*
G01X1197127Y314264D02*
X1180808Y297945D01*
G01D02*
Y290340D01*
X1176590Y286122D01*
G01X1345000Y144900D02*
X1344600Y145300D01*
Y149600D01*
X1344800Y149800D01*
G01X1334140Y146642D02*
X1330387D01*
X1328100Y148929D01*
Y153425D01*
G01X1340100Y155015D02*
X1341200Y156115D01*
Y160300D01*
G01D02*
X1338400D01*
X1336900Y158800D01*
X1334100D01*
G01X1345500Y165500D02*
X1341200Y161200D01*
Y160300D01*
G01X1350000Y154800D02*
X1349200Y155600D01*
X1344800D01*
G01X1324100Y153425D02*
Y150500D01*
G01X1328100Y153425D02*
X1330875D01*
X1334100Y150200D01*
G01X1350100Y199250D02*
X1349850Y199500D01*
X1344800D01*
G01X1334100Y203200D02*
X1336900D01*
X1338100Y204400D01*
X1341200D01*
G01D02*
Y207900D01*
X1342900Y209600D01*
G01X1340600Y199401D02*
X1341200Y200001D01*
Y204400D01*
G01X1324100Y197825D02*
Y194900D01*
G01X1334100Y194600D02*
X1330875Y197825D01*
X1328100D01*
G01X1344500Y188900D02*
Y191200D01*
X1344800Y191500D01*
Y193700D01*
G01X1332671Y190644D02*
X1331017D01*
X1328100Y193561D01*
Y197825D01*
G01X1349600Y149500D02*
Y154400D01*
X1350000Y154800D01*
G01X1349600Y194000D02*
Y196900D01*
X1350100Y197400D01*
Y199250D01*
X3018Y23930D03*
X10493Y5830D03*
X3018Y43930D03*
Y83930D03*
Y63930D03*
Y103930D03*
Y143930D03*
Y123930D03*
Y163930D03*
Y203930D03*
Y183930D03*
Y223930D03*
Y263930D03*
Y243930D03*
Y283930D03*
Y323930D03*
Y303930D03*
Y343930D03*
Y383930D03*
Y363930D03*
Y403930D03*
Y443930D03*
Y423930D03*
Y463930D03*
Y503930D03*
Y483930D03*
Y523930D03*
Y563930D03*
Y543930D03*
Y583930D03*
X15642Y619715D03*
X3018Y603930D03*
X30709Y3014D03*
X35455Y620194D03*
X75455D03*
X55455D03*
X81406Y3042D03*
X101406D03*
X95455Y620194D03*
X121406Y3042D03*
X114923Y623982D03*
X124901Y640105D03*
X161406Y3042D03*
X141406D03*
X154778Y672779D03*
X181406Y3042D03*
X187600Y106500D03*
X176785Y102000D03*
X194778Y672779D03*
X174778D03*
X201406Y3042D03*
X221406D03*
X205061Y85500D03*
Y79000D03*
Y75000D03*
Y71500D03*
Y89500D03*
Y97000D03*
X225829Y103412D03*
Y99503D03*
X225953Y95780D03*
X225891Y92305D03*
X205100Y123000D03*
X214778Y672779D03*
X229829Y103412D03*
X233329D03*
X237329D03*
X229829Y99503D03*
X233329D03*
X237329D03*
X229953Y95780D03*
X233453D03*
X237453D03*
X229891Y92305D03*
X233391D03*
X237391D03*
X254778Y672779D03*
X234778D03*
X274778D03*
X314766Y39211D03*
X317766D03*
X317000Y74475D03*
Y64500D03*
X311956Y651522D03*
X294778Y672779D03*
X325500Y15000D03*
Y18000D03*
Y21000D03*
X340500D03*
Y18000D03*
Y15000D03*
X337500Y21000D03*
Y18000D03*
Y15000D03*
X334500Y21000D03*
Y18000D03*
Y15000D03*
X331500Y21000D03*
Y18000D03*
Y15000D03*
X328500Y21000D03*
Y18000D03*
Y15000D03*
X323766Y39211D03*
X320766D03*
X321500Y74475D03*
X325100Y64000D03*
X330500Y74476D03*
X324000Y77000D03*
X321000Y63000D03*
X326000Y74476D03*
X345412Y435017D03*
Y455017D03*
Y475017D03*
Y495017D03*
Y515017D03*
Y535017D03*
Y555017D03*
Y575017D03*
Y595017D03*
X342119Y613510D03*
X331285Y620008D03*
X369192Y38417D03*
X372192D03*
X378192D03*
X375192D03*
X362127Y406608D03*
X350024Y418335D03*
X408100Y180100D03*
Y224500D03*
X399680Y402510D03*
X379680D03*
X428277Y167056D03*
X438100Y170000D03*
X430608Y211389D03*
X438100Y214500D03*
X419680Y402510D03*
X454738Y56000D03*
X451738D03*
X448738D03*
X445738D03*
X442738D03*
X454738Y68000D03*
Y65000D03*
Y62000D03*
Y59000D03*
X451738D03*
Y62000D03*
Y65000D03*
Y68000D03*
X448738Y59000D03*
Y62000D03*
Y65000D03*
Y68000D03*
X445738Y59000D03*
Y62000D03*
Y65000D03*
Y68000D03*
X442738Y59000D03*
Y62000D03*
Y65000D03*
Y68000D03*
X441938Y87700D03*
X454738Y112400D03*
Y109400D03*
Y106400D03*
Y103400D03*
X451738D03*
Y106400D03*
Y109400D03*
Y112400D03*
X448738Y103400D03*
Y106400D03*
Y109400D03*
Y112400D03*
X445738Y103400D03*
Y106400D03*
Y109400D03*
Y112400D03*
X442738Y103400D03*
Y106400D03*
Y109400D03*
Y112400D03*
X454738Y100400D03*
X451738D03*
X448738D03*
X445738D03*
X442738D03*
X454738Y147800D03*
X451738D03*
X448738D03*
X445738D03*
X442738D03*
X454738Y144800D03*
X451738D03*
X448738D03*
X445738D03*
X442738D03*
X454738Y156800D03*
Y153800D03*
Y150800D03*
X451738D03*
Y153800D03*
Y156800D03*
X448738Y150800D03*
Y153800D03*
Y156800D03*
X445738Y150800D03*
Y153800D03*
Y156800D03*
X442738Y150800D03*
Y153800D03*
Y156800D03*
X441938Y176500D03*
X454738Y201200D03*
Y198200D03*
Y195200D03*
Y192200D03*
X451738D03*
Y195200D03*
Y198200D03*
Y201200D03*
X448738Y192200D03*
Y195200D03*
Y198200D03*
Y201200D03*
X445738Y192200D03*
Y195200D03*
Y198200D03*
Y201200D03*
X442738Y192200D03*
Y195200D03*
Y198200D03*
Y201200D03*
X454738Y189200D03*
X451738D03*
X448738D03*
X445738D03*
X442738D03*
X454738Y239600D03*
Y236600D03*
X451738D03*
Y239600D03*
X448738Y236600D03*
Y239600D03*
X445738Y236600D03*
Y239600D03*
X442738Y236600D03*
Y239600D03*
X454738Y233600D03*
X451738D03*
X448738D03*
X445738D03*
X442738D03*
X441938Y220900D03*
X454738Y245600D03*
Y242600D03*
X451738D03*
Y245600D03*
X448738Y242600D03*
Y245600D03*
X445738Y242600D03*
Y245600D03*
X442738Y242600D03*
Y245600D03*
X441938Y265300D03*
X448738Y278000D03*
X451738D03*
X454738D03*
X448738Y290000D03*
Y287000D03*
Y284000D03*
Y281000D03*
X451738Y290000D03*
Y287000D03*
Y284000D03*
Y281000D03*
X454738D03*
Y284000D03*
Y287000D03*
Y290000D03*
X445738D03*
Y287000D03*
Y284000D03*
Y281000D03*
Y278000D03*
X442738Y290000D03*
Y287000D03*
Y284000D03*
Y281000D03*
Y278000D03*
X468946Y338216D03*
X465946D03*
X468946Y341216D03*
X465946D03*
X458946Y338216D03*
X455946D03*
Y341216D03*
X458946Y357216D03*
X468946Y357016D03*
X459680Y402510D03*
X439680D03*
X498923Y37456D03*
X495923D03*
X492923D03*
X489923D03*
X471946Y338216D03*
X481446D03*
X478446D03*
X481446Y341216D03*
X478446D03*
X484446Y338216D03*
X471946Y357016D03*
X479680Y402510D03*
X501923Y37456D03*
X504923D03*
X510923D03*
X507923D03*
X528084Y77900D03*
Y74900D03*
Y71900D03*
Y68900D03*
Y65900D03*
X525084Y77900D03*
Y74900D03*
Y71900D03*
Y68900D03*
Y65900D03*
X522084Y77900D03*
Y74900D03*
Y71900D03*
Y68900D03*
Y65900D03*
X525084Y116300D03*
Y113300D03*
Y110300D03*
X522084Y113300D03*
Y116300D03*
Y110300D03*
X528084Y116300D03*
Y113300D03*
Y110300D03*
X525084Y122300D03*
X522084D03*
X525084Y119300D03*
X522084D03*
X528084Y122300D03*
Y119300D03*
X525084Y166700D03*
X522084D03*
X525084Y160700D03*
Y163700D03*
Y157700D03*
Y154700D03*
X522084Y157700D03*
Y163700D03*
Y160700D03*
Y154700D03*
Y199100D03*
Y205100D03*
Y208100D03*
Y202100D03*
X525084Y199100D03*
Y202100D03*
Y208100D03*
Y205100D03*
X522084Y211100D03*
X525084D03*
X522084Y243500D03*
Y249500D03*
Y252500D03*
Y246500D03*
X525084Y243500D03*
Y246500D03*
Y252500D03*
Y249500D03*
X522084Y255500D03*
X525084D03*
X528084Y243500D03*
Y246500D03*
Y252500D03*
Y249500D03*
Y255500D03*
Y299900D03*
X525084D03*
X522084D03*
X528084Y296900D03*
X525084D03*
X522084D03*
X528084Y293900D03*
X525084D03*
X522084D03*
X528084Y290900D03*
Y287900D03*
X525084D03*
Y290900D03*
X522084D03*
Y287900D03*
X499680Y402510D03*
X519680D03*
X531084Y77900D03*
Y74900D03*
Y71900D03*
Y68900D03*
Y65900D03*
X561155Y160784D03*
X551430Y265600D03*
X531084Y299900D03*
Y296900D03*
Y293900D03*
Y290900D03*
Y287900D03*
X539680Y402510D03*
X559680D03*
X586184Y117800D03*
X583184D03*
X586184Y114800D03*
X583184D03*
X580184D03*
X583184Y111800D03*
X580184D03*
X586184Y108800D03*
X583184D03*
X580184D03*
X586184Y105800D03*
X583184D03*
X563007Y118477D03*
Y114123D03*
X580184Y126800D03*
X583184D03*
X586184D03*
Y123800D03*
X583184D03*
X580184D03*
X586184Y120800D03*
X583184D03*
X580184D03*
X562830Y133300D03*
Y136800D03*
Y143800D03*
X564305Y160784D03*
X583184Y239000D03*
X580184D03*
X576467Y265600D03*
X563007Y247323D03*
X583184Y242000D03*
X580184D03*
X583184Y254000D03*
Y251000D03*
Y248000D03*
Y245000D03*
X580184D03*
Y248000D03*
Y251000D03*
Y254000D03*
X583184Y260000D03*
Y257000D03*
X580184D03*
Y260000D03*
X562830Y270000D03*
X590298Y282890D03*
X562830Y277000D03*
X571325Y292757D03*
X590298Y276984D03*
X562830Y273500D03*
X565091Y302592D03*
X570443Y302702D03*
X579680Y402510D03*
X595276Y239710D03*
X592476D03*
X620600Y239161D03*
X620466Y246839D03*
X605800Y256500D03*
X609637Y254523D03*
X605700Y259500D03*
X616184Y267000D03*
X604684D03*
X612684Y297000D03*
X616684Y294500D03*
X602928Y293969D03*
X606084Y293100D03*
X600875Y295937D03*
X616184Y276000D03*
X604684D03*
Y285000D03*
X616184D03*
X590684Y313800D03*
Y310800D03*
X601675Y305575D03*
X616684Y307975D03*
X622184Y308000D03*
X608259Y305000D03*
X618500Y333500D03*
X619680Y402510D03*
X599680D03*
X645784Y43500D03*
X648784D03*
X645784Y40500D03*
X648784D03*
X645784Y99000D03*
X648784D03*
X645784Y96000D03*
X648784D03*
X622288Y235790D03*
X624788D03*
X639010Y236377D03*
X640684Y264500D03*
Y269000D03*
X641000Y261500D03*
X645900Y242200D03*
X644502Y246839D03*
X649200Y254500D03*
X650100Y251500D03*
X623684Y281000D03*
X637684Y280575D03*
X629018Y277500D03*
X625684Y273499D03*
X630308Y284500D03*
X649059Y314000D03*
X632186Y338917D03*
X623500Y379000D03*
X639680Y402510D03*
X651784Y43500D03*
Y40500D03*
X654784D03*
X657784Y43500D03*
X654784D03*
X651784Y99000D03*
Y96000D03*
X654784D03*
X657784Y99000D03*
X654784D03*
X658600Y237700D03*
X655600D03*
X664484Y212500D03*
X666984D03*
X672484D03*
X674984D03*
X679484D03*
X657259Y263000D03*
X674800Y269600D03*
X660684Y262500D03*
X654100Y263000D03*
X651100Y266000D03*
X679184Y278980D03*
X673684Y280950D03*
X676684D03*
X670184Y288500D03*
X662184Y280500D03*
Y288500D03*
Y284500D03*
X659000Y284000D03*
X679184Y273190D03*
X676184Y274000D03*
X657500Y330075D03*
X662075Y320000D03*
X662125Y308500D03*
X671000Y315760D03*
X668000Y311500D03*
X663500D03*
X657500Y326925D03*
X662100Y304500D03*
X658925Y320000D03*
X659680Y402510D03*
X679680D03*
X693863Y189760D03*
X688900Y184260D03*
X704200Y206569D03*
X704240Y185000D03*
X681984Y212500D03*
X685484D03*
X687984D03*
X683592Y259908D03*
X688945Y259761D03*
X695259Y248020D03*
X706984Y261100D03*
X710084D03*
X691794Y261073D03*
X692109Y248020D03*
X686784Y268100D03*
X695584D03*
X698433Y247119D03*
X685884Y297000D03*
X702984Y283500D03*
X706684D03*
X702984Y272400D03*
X706684D03*
X686784Y278000D03*
X695584D03*
X686784Y287900D03*
X695684D03*
X710900Y324100D03*
X696613Y324032D03*
X693904D03*
X691759Y309000D03*
X699680Y402510D03*
X736554Y131056D03*
Y128056D03*
X739554Y131056D03*
Y128056D03*
X742554D03*
X732100Y185000D03*
X729100D03*
X726100D03*
X723100D03*
X726100Y188000D03*
X729100D03*
X732100D03*
X723100D03*
X720100D03*
X726000Y231500D03*
X729000D03*
X723000D03*
X720000D03*
X732000D03*
Y228500D03*
X720000D03*
X723000D03*
X726000D03*
X729000D03*
X712000Y215500D03*
X730600Y270000D03*
X727600D03*
X717384Y273400D03*
X719484Y278980D03*
X722925Y299500D03*
X719433Y328087D03*
X734500Y307425D03*
X719500Y315500D03*
X734500Y310575D03*
X717401Y329996D03*
X739680Y402510D03*
X719680D03*
X742554Y131056D03*
X770700Y206900D03*
X749600Y185000D03*
X752600D03*
X755600D03*
X746600Y188000D03*
X758600D03*
X755600D03*
X752600D03*
X749600D03*
X746600Y185000D03*
X758500Y231500D03*
X746500D03*
X755500D03*
X752500D03*
X749500D03*
X746500Y228500D03*
X755500D03*
X752500D03*
X749500D03*
X758500D03*
X759680Y402510D03*
X776000Y206600D03*
X779680Y402510D03*
X799680D03*
X819680D03*
X862600Y29500D03*
X839680Y402510D03*
X859680D03*
X867100Y28000D03*
X872533Y29432D03*
X867100Y31500D03*
X887500Y355680D03*
X885265Y381000D03*
X878175Y374100D03*
Y364709D03*
X880500Y369500D03*
X879680Y402510D03*
X919680D03*
X899680D03*
X894500Y396500D03*
X954200Y200200D03*
X954600Y207200D03*
X939680Y402510D03*
X983500Y185000D03*
Y188000D03*
X980500Y185000D03*
X977500D03*
X980500Y188000D03*
X977500D03*
X974500D03*
Y231500D03*
X977500D03*
X983500D03*
X980500D03*
X983500Y228500D03*
X980500D03*
X977500D03*
X974500D03*
X959680Y402510D03*
X979680D03*
X990954Y131056D03*
Y128056D03*
X993954Y131056D03*
Y128056D03*
X996954D03*
Y131056D03*
X986500Y185000D03*
Y188000D03*
X1004000Y185000D03*
X1001000Y188000D03*
X1004000D03*
X1007000Y185000D03*
X1010000D03*
X1013000Y188000D03*
X1010000D03*
X1007000D03*
X1001000Y185000D03*
X1004000Y231500D03*
X1007000D03*
X1010000D03*
X1001000D03*
X986500D03*
X1013000D03*
X986500Y228500D03*
X1013000D03*
X1004000D03*
X1007000D03*
X1010000D03*
X1001000D03*
X999680Y402510D03*
X1030100Y207500D03*
X1034537Y201437D03*
X1024600Y185000D03*
X1027675Y215000D03*
X1024525D03*
X1032500Y281800D03*
X1029500D03*
X1044900Y278600D03*
X1042800Y273020D03*
X1017300Y322500D03*
X1026270Y303729D03*
X1023492Y346593D03*
X1039680Y402510D03*
X1019680D03*
X1047163Y197437D03*
X1061600Y228000D03*
X1064600D03*
X1073600D03*
X1070600D03*
X1066600Y264100D03*
X1074430Y256461D03*
X1059300Y268500D03*
X1055600D03*
X1070525Y243000D03*
X1066700Y274000D03*
Y283900D03*
X1052200Y290900D03*
X1055300D03*
X1070490Y290927D03*
X1055600Y279600D03*
X1059300D03*
X1073339Y292239D03*
X1062600Y305000D03*
X1070175Y303980D03*
X1067025D03*
X1072600Y324000D03*
X1064600D03*
X1065800Y339500D03*
X1063300D03*
X1073800D03*
X1071300D03*
X1059680Y402510D03*
X1077500Y43500D03*
Y40500D03*
X1074500D03*
X1080500D03*
X1083500D03*
X1086500D03*
X1080500Y43500D03*
X1083500D03*
X1086500D03*
X1077500Y99000D03*
Y96000D03*
X1074500D03*
X1080500D03*
X1083500D03*
X1086500D03*
X1080500Y99000D03*
X1083500D03*
X1086500D03*
X1092100Y263500D03*
X1100100Y243500D03*
X1100500Y263500D03*
X1101500Y268500D03*
X1100100Y247500D03*
X1075500Y264100D03*
X1085600Y271050D03*
X1101500Y271500D03*
X1083100Y273020D03*
X1088079Y274980D03*
X1087100Y282500D03*
X1101600Y289500D03*
X1080600Y294000D03*
X1075500Y274000D03*
Y283900D03*
X1102600Y296000D03*
X1083100Y278810D03*
X1086100Y278000D03*
X1103661Y307700D03*
X1080600Y324000D03*
X1081800Y339500D03*
X1079300D03*
X1086800D03*
X1089300D03*
X1094500Y355600D03*
Y360500D03*
X1079680Y402510D03*
X1099680D03*
X1129800Y265400D03*
X1131976Y267500D03*
X1108100Y289000D03*
X1121600Y287500D03*
Y283000D03*
X1118500D03*
X1105025Y289000D03*
X1111100Y291500D03*
Y285000D03*
X1121100Y296000D03*
X1124600Y271425D03*
X1132113Y274500D03*
X1112000Y296000D03*
X1106661Y307700D03*
X1111100Y300500D03*
X1118000Y303500D03*
X1123100Y322500D03*
Y319500D03*
X1130100Y305174D03*
X1130510Y307720D03*
X1123400Y356300D03*
X1106000Y364500D03*
X1112500Y364700D03*
X1122000Y366240D03*
X1132000Y367000D03*
X1119680Y402510D03*
X1155366Y38982D03*
X1152366D03*
X1158366D03*
X1161366D03*
X1145600Y257500D03*
X1143500Y251500D03*
X1149600Y255000D03*
X1160990Y252134D03*
X1146100Y267000D03*
X1157600D03*
X1156200Y258900D03*
X1145600Y244025D03*
X1140100Y244000D03*
X1154025Y247000D03*
X1163266Y255311D03*
X1156584Y292488D03*
X1156509Y295396D03*
X1157600Y276000D03*
X1146100D03*
Y285000D03*
X1157600D03*
X1136000Y278953D03*
X1141600Y305161D03*
X1154600Y321050D03*
X1143100Y322500D03*
Y320000D03*
X1157800Y312050D03*
X1157138Y303000D03*
X1141600Y312839D03*
X1141500Y347500D03*
X1138500D03*
X1162425Y340500D03*
X1147000Y342500D03*
X1163000Y352500D03*
X1153500Y342500D03*
X1135000Y366500D03*
X1139000D03*
X1159680Y402510D03*
X1139680D03*
X1176100Y105800D03*
Y108800D03*
X1182100D03*
X1179100D03*
Y105800D03*
X1176100Y111800D03*
Y114800D03*
Y117800D03*
X1182100Y111800D03*
Y114800D03*
Y117800D03*
X1179100D03*
Y114800D03*
Y111800D03*
X1176100Y126800D03*
Y123800D03*
Y120800D03*
X1182100Y126800D03*
Y123800D03*
Y120800D03*
X1179100D03*
Y123800D03*
Y126800D03*
X1187700Y132400D03*
X1197425Y160284D03*
X1176100Y239000D03*
X1171600Y238000D03*
X1179100Y239000D03*
X1182100D03*
X1187700Y265600D03*
X1176100Y254000D03*
Y251000D03*
Y248000D03*
Y245000D03*
Y257000D03*
Y260000D03*
Y242000D03*
X1171600Y241500D03*
X1179100Y242000D03*
Y260000D03*
Y257000D03*
Y245000D03*
Y248000D03*
Y251000D03*
Y254000D03*
X1182100D03*
Y251000D03*
Y248000D03*
Y245000D03*
Y257000D03*
Y260000D03*
Y242000D03*
X1171986Y269110D03*
X1173500Y298500D03*
X1196500Y293284D03*
X1171986Y275016D03*
X1176200Y316500D03*
X1173200D03*
X1167800Y355000D03*
X1168200Y349700D03*
X1165575Y340500D03*
X1171700Y349900D03*
X1178900Y359620D03*
X1179500Y350000D03*
Y355000D03*
X1178500Y368740D03*
X1179680Y402510D03*
X1223866Y38482D03*
X1220866D03*
X1199277Y118477D03*
Y114123D03*
X1199100Y140300D03*
Y133300D03*
Y143800D03*
Y136800D03*
X1200575Y160284D03*
X1199277Y247323D03*
Y251677D03*
X1199100Y270000D03*
Y266500D03*
X1201500Y293284D03*
X1199100Y277000D03*
Y273500D03*
X1201037Y318912D03*
X1197127Y314264D03*
X1199680Y402510D03*
X1219680D03*
X1226866Y38482D03*
X1229866D03*
X1240200Y77900D03*
Y74900D03*
Y71900D03*
Y68900D03*
Y65900D03*
X1237200D03*
Y68900D03*
Y71900D03*
Y74900D03*
Y77900D03*
X1234200Y65900D03*
Y68900D03*
Y71900D03*
Y74900D03*
Y77900D03*
X1231200Y65900D03*
Y68900D03*
Y71900D03*
Y74900D03*
Y77900D03*
X1234200Y116300D03*
Y113300D03*
Y110300D03*
X1237200Y116300D03*
Y113300D03*
Y110300D03*
X1240200D03*
Y113300D03*
Y116300D03*
X1234200Y122300D03*
Y119300D03*
X1237200Y122300D03*
Y119300D03*
X1240200D03*
Y122300D03*
X1237200Y166700D03*
Y163700D03*
Y160700D03*
Y157700D03*
Y154700D03*
X1240200D03*
Y157700D03*
Y160700D03*
Y163700D03*
Y166700D03*
X1237200Y205100D03*
Y202100D03*
Y199100D03*
Y208100D03*
X1240200D03*
Y199100D03*
Y202100D03*
Y205100D03*
X1237200Y211100D03*
X1240200D03*
X1234200Y249500D03*
Y246500D03*
Y243500D03*
Y252500D03*
X1237200Y249500D03*
Y246500D03*
Y243500D03*
Y252500D03*
X1234200Y255500D03*
X1237200D03*
X1240200Y252500D03*
Y243500D03*
Y246500D03*
Y249500D03*
Y255500D03*
Y293900D03*
Y290900D03*
Y287900D03*
Y299900D03*
Y296900D03*
X1237200D03*
Y287900D03*
Y290900D03*
Y293900D03*
Y299900D03*
X1234200Y296900D03*
Y287900D03*
Y290900D03*
Y293900D03*
Y299900D03*
X1231200Y293900D03*
Y290900D03*
Y287900D03*
Y296900D03*
Y299900D03*
X1242930Y356148D03*
X1245930Y359148D03*
Y356148D03*
X1248930Y359148D03*
Y356148D03*
X1231930D03*
Y359148D03*
X1228930Y356148D03*
Y359148D03*
X1225930Y356148D03*
X1253930Y379648D03*
X1250930D03*
X1247930D03*
X1239680Y402510D03*
X1264366Y38482D03*
X1261366D03*
X1267366D03*
X1270366D03*
X1260340Y356284D03*
X1263340Y359284D03*
Y356284D03*
X1266340Y359284D03*
Y356284D03*
X1265340Y379784D03*
X1268340D03*
X1271340D03*
X1259680Y402510D03*
X1279680D03*
X1313366Y38482D03*
X1307366D03*
X1310366D03*
X1307700Y78900D03*
Y81900D03*
X1310700D03*
Y78900D03*
X1313700Y81900D03*
Y78900D03*
X1307700Y84900D03*
Y87900D03*
X1310700D03*
Y84900D03*
X1313700Y87900D03*
Y84900D03*
X1307700Y90900D03*
X1310700D03*
X1313700D03*
X1307700Y123300D03*
Y126300D03*
X1310700D03*
Y123300D03*
X1313700Y126300D03*
Y123300D03*
X1307700Y129300D03*
Y132300D03*
Y135300D03*
X1310700D03*
Y132300D03*
Y129300D03*
X1313700Y135300D03*
Y132300D03*
Y129300D03*
Y167700D03*
Y170700D03*
Y173700D03*
Y176700D03*
X1310700Y167700D03*
Y170700D03*
Y173700D03*
Y176700D03*
X1307700D03*
Y173700D03*
Y170700D03*
Y167700D03*
X1313700Y179700D03*
X1310700D03*
X1307700D03*
Y212100D03*
Y215100D03*
X1310700D03*
Y212100D03*
X1313700Y215100D03*
Y212100D03*
X1307700Y218100D03*
Y221100D03*
Y224100D03*
X1310700D03*
Y221100D03*
Y218100D03*
X1313700Y224100D03*
Y221100D03*
Y218100D03*
X1307700Y256500D03*
Y259500D03*
X1310700D03*
Y256500D03*
X1313700Y259500D03*
Y256500D03*
X1307700Y262500D03*
Y265500D03*
Y268500D03*
X1310700D03*
Y265500D03*
Y262500D03*
X1313700Y268500D03*
Y265500D03*
Y262500D03*
X1307700Y300900D03*
Y303900D03*
X1310700D03*
Y300900D03*
X1313700Y303900D03*
Y300900D03*
X1307700Y306900D03*
Y309900D03*
Y312900D03*
X1310700D03*
Y309900D03*
Y306900D03*
X1313700Y309900D03*
Y306900D03*
X1286113Y375312D03*
X1289113Y378312D03*
Y375312D03*
X1292113Y378312D03*
Y375312D03*
Y372312D03*
X1289113D03*
X1299680Y402510D03*
X1316366Y38482D03*
X1316700Y81900D03*
Y78900D03*
X1319700Y81900D03*
Y78900D03*
X1316700Y87900D03*
Y84900D03*
X1319700Y87900D03*
Y84900D03*
X1320346Y67900D03*
X1316700Y90900D03*
X1319700D03*
X1316700Y126300D03*
Y123300D03*
X1319700Y126300D03*
Y123300D03*
X1316700Y135300D03*
Y132300D03*
Y129300D03*
X1319700Y135300D03*
Y132300D03*
Y129300D03*
X1334140Y146642D03*
X1319700Y167700D03*
Y170700D03*
Y173700D03*
Y176700D03*
X1316700Y167700D03*
Y170700D03*
Y173700D03*
Y176700D03*
X1324100Y150500D03*
X1320346Y156700D03*
X1324100Y194900D03*
X1332671Y190644D03*
X1320346Y201100D03*
X1316700Y215100D03*
Y212100D03*
X1319700Y215100D03*
Y212100D03*
X1316700Y224100D03*
Y221100D03*
Y218100D03*
X1319700Y224100D03*
Y221100D03*
Y218100D03*
X1316700Y259500D03*
Y256500D03*
X1319700Y259500D03*
Y256500D03*
X1316700Y268500D03*
Y265500D03*
Y262500D03*
X1319700Y268500D03*
Y265500D03*
Y262500D03*
X1320346Y245500D03*
X1316700Y303900D03*
Y300900D03*
X1319700Y303900D03*
Y300900D03*
X1316700Y306900D03*
X1339680Y402510D03*
X1319680D03*
X1355310Y38893D03*
X1352310D03*
X1349310D03*
X1358310D03*
X1355100Y160000D03*
X1355000Y204400D03*
X1359620Y402940D03*
X1406230Y21076D03*
Y18076D03*
X1403230Y21076D03*
Y18076D03*
Y15076D03*
X1400230Y18076D03*
Y15076D03*
X1397230D03*
Y18076D03*
Y21076D03*
X1386882Y434539D03*
Y454539D03*
Y474539D03*
Y494539D03*
Y514539D03*
Y534539D03*
Y554539D03*
Y574539D03*
Y594539D03*
X1389643Y612723D03*
X1403035Y620181D03*
X1412230Y18076D03*
Y15076D03*
X1409230Y21076D03*
Y18076D03*
Y15076D03*
X1422310Y40481D03*
X1419310D03*
X1416310D03*
X1425310D03*
X1420335Y635388D03*
Y655388D03*
X1428754Y670547D03*
X1445829Y672778D03*
X1465829D03*
X1498180Y63500D03*
X1494728Y83500D03*
X1490000Y84000D03*
X1494728Y66500D03*
X1491918Y107773D03*
Y110773D03*
Y113773D03*
Y104773D03*
X1488918D03*
Y113773D03*
Y110773D03*
Y107773D03*
X1485918Y104773D03*
Y113773D03*
Y110773D03*
Y107773D03*
X1482918Y104773D03*
Y113773D03*
Y110773D03*
Y107773D03*
X1485829Y672778D03*
X1508460Y3003D03*
X1503728Y74477D03*
X1527100Y108500D03*
Y98925D03*
X1524600Y111500D03*
X1505829Y672778D03*
X1525829D03*
X1548460Y3003D03*
X1528460D03*
X1531600Y96941D03*
X1545829Y672778D03*
X1588460Y3003D03*
X1568460D03*
X1565829Y672778D03*
X1585829D03*
X1608460Y3003D03*
X1609100Y85500D03*
Y82000D03*
X1606100Y85500D03*
Y82000D03*
X1609100Y69500D03*
Y66000D03*
Y62500D03*
X1606100Y69500D03*
Y66000D03*
Y62500D03*
X1615800Y82700D03*
Y79700D03*
Y76700D03*
X1602100Y85500D03*
Y82000D03*
Y69500D03*
Y66000D03*
Y62500D03*
X1594930Y115000D03*
X1614100Y110000D03*
Y115000D03*
X1609100Y89000D03*
X1606100D03*
X1602100D03*
X1614100Y125000D03*
Y120000D03*
Y130000D03*
X1618100Y148925D03*
X1613527Y627220D03*
X1607226Y650448D03*
X1602599Y667628D03*
X1648460Y3003D03*
X1628460D03*
X1618800Y79700D03*
Y82700D03*
X1647800Y83200D03*
Y77200D03*
Y80200D03*
X1622295Y114940D03*
X1629870Y104240D03*
X1642037Y104134D03*
X1643537Y101434D03*
X1640037D03*
X1638537Y104134D03*
X1645537D03*
X1647037Y101434D03*
X1624500Y142500D03*
Y146000D03*
X1622295Y118940D03*
X1647837Y121812D03*
X1638707Y132954D03*
X1644917Y124581D03*
X1623100Y172500D03*
Y178000D03*
X1636600Y173500D03*
X1626000Y163500D03*
Y167500D03*
X1626925Y156000D03*
X1629000Y175000D03*
X1631585Y188777D03*
X1624000Y189000D03*
X1642000Y184500D03*
X1645000D03*
X1628658Y620261D03*
X1648675Y620226D03*
X1657050Y102380D03*
X1662000Y106000D03*
X1660250Y113860D03*
X1657050D03*
X1660250Y116760D03*
X1651037Y99734D03*
X1658500Y138000D03*
X1649197Y132915D03*
X1650990Y122034D03*
X1667000Y138000D03*
X1672800Y120400D03*
X1649500Y173398D03*
X1657500Y191500D03*
X1661500Y199000D03*
X1667600Y198500D03*
X1658000Y179500D03*
X1652600Y212000D03*
X1668675Y620226D03*
X1708460Y3003D03*
X1692000Y76570D03*
X1695500Y76500D03*
X1682500Y121825D03*
X1697976Y148000D03*
X1690100Y127375D03*
X1685976Y148000D03*
X1705100Y140500D03*
X1707100Y142500D03*
X1702600Y171500D03*
X1697976Y164500D03*
Y159000D03*
Y175500D03*
Y170000D03*
Y153500D03*
X1680000Y156500D03*
X1685976Y164500D03*
Y159000D03*
Y175500D03*
Y170000D03*
X1701100Y178500D03*
X1701000Y159000D03*
Y164500D03*
X1685975Y186500D03*
X1697975Y181000D03*
X1704600Y201500D03*
X1685976Y181000D03*
X1688692Y620191D03*
X1708692D03*
X1729255Y25347D03*
Y45347D03*
X1718675Y88000D03*
X1732786Y58461D03*
X1719075Y112000D03*
X1718675Y99000D03*
Y93500D03*
X1713524Y109500D03*
Y114500D03*
X1738000Y124500D03*
X1713525Y134500D03*
Y129500D03*
X1713524Y119500D03*
X1715525Y153000D03*
X1720524Y175000D03*
X1717600Y158000D03*
X1712000Y153000D03*
X1728475Y175000D03*
X1731925Y199000D03*
X1714175Y187000D03*
X1729000Y183500D03*
X1724824Y205276D03*
X1711025Y187000D03*
X1721500Y205000D03*
X1721600Y194760D03*
Y198500D03*
X1728600Y387500D03*
X1731100D03*
X1733600D03*
Y397500D03*
X1731100D03*
X1728600D03*
X1729275Y562751D03*
Y542751D03*
Y582751D03*
Y602751D03*
X1753635Y69037D03*
X1767525Y114016D03*
X1764000Y107000D03*
X1763500Y113000D03*
X1767425Y137000D03*
X1768500Y142525D03*
X1764100Y119500D03*
X1764000Y158025D03*
X1759925Y178900D03*
X1768500Y158025D03*
X1763925Y170984D03*
Y155484D03*
X1766925Y181500D03*
X1769425Y203000D03*
X1754925D03*
X1754260Y187260D03*
X1768000D03*
X1746000Y191240D03*
X1750563Y198000D03*
X1751600Y238000D03*
Y235500D03*
X1740600D03*
Y238000D03*
X1751600Y233000D03*
X1740600D03*
X1751600Y258000D03*
Y255500D03*
X1740600Y258000D03*
Y255500D03*
Y248000D03*
Y250500D03*
Y253000D03*
X1751600D03*
Y250500D03*
Y248000D03*
X1766432Y250301D03*
Y247301D03*
X1766447Y239798D03*
Y242798D03*
X1751600Y240500D03*
X1740600D03*
X1742109Y345235D03*
Y342435D03*
X1747416Y348293D03*
X1751289Y345227D03*
X1747909Y345335D03*
Y342535D03*
X1744909Y345335D03*
Y342535D03*
X1747416Y351817D03*
X1747235Y359564D03*
X1742109Y339635D03*
Y336835D03*
Y334035D03*
X1747909Y339735D03*
Y336935D03*
Y334135D03*
X1744909Y339735D03*
Y336935D03*
Y334135D03*
X1767151Y333311D03*
X1767600Y350000D03*
X1747235Y367264D03*
Y374964D03*
X1755454Y515746D03*
X1793635Y69037D03*
X1773635D03*
X1772975Y109500D03*
Y104500D03*
X1773076Y117500D03*
X1773500Y121000D03*
X1772975Y124500D03*
X1772500Y174000D03*
X1800100Y187500D03*
X1770075Y181500D03*
X1778000Y189500D03*
X1789600Y247000D03*
X1783932Y250357D03*
Y247357D03*
X1775432Y250357D03*
Y247357D03*
X1783947Y239798D03*
Y242798D03*
X1775447Y239798D03*
Y242798D03*
X1789600Y243500D03*
X1777532Y328322D03*
X1777375Y356300D03*
X1777459Y332322D03*
X1777383Y348288D03*
Y352305D03*
X1776100Y361500D03*
Y371500D03*
Y368500D03*
X1776140Y364405D03*
X1784035Y389535D03*
X1781535D03*
X1784035Y386935D03*
X1781535D03*
X1778838Y389508D03*
Y386908D03*
X1781535Y402935D03*
X1784035D03*
X1778838Y402908D03*
X1781535Y405535D03*
X1784035D03*
X1778838Y405508D03*
X1775454Y515746D03*
X1813635Y69037D03*
X1809600Y195000D03*
X1815454Y515746D03*
X1853635Y69037D03*
X1833635D03*
X1842164Y419238D03*
X1837164D03*
X1852164D03*
X1844500Y416500D03*
X1847500Y437000D03*
X1835454Y515746D03*
X1855509Y515697D03*
X1871008Y117112D03*
X1871009Y93913D03*
X1871008Y137112D03*
Y177112D03*
Y157112D03*
Y197112D03*
Y237112D03*
Y217112D03*
Y257112D03*
Y297112D03*
Y277112D03*
Y317112D03*
Y357112D03*
Y337112D03*
Y377112D03*
Y417112D03*
Y397112D03*
Y437112D03*
Y477112D03*
Y457112D03*
Y497112D03*
G54D12*
X32284Y555118D03*
X59055Y511811D03*
X1673228D03*
X1700000Y555118D03*
G54D30*
X434100Y173116D03*
Y217516D03*
X438100D03*
X607684Y249516D03*
X612684Y302516D03*
X616684D03*
X635184Y277516D03*
X680100Y249516D03*
X676100D03*
X672184D03*
X688184D03*
X684184D03*
X699684D03*
X1127100Y255516D03*
Y247516D03*
X1149600Y238016D03*
X1145600D03*
X1140100Y246516D03*
X1163000Y344516D03*
X1328100Y153516D03*
X1324100Y197916D03*
X1328100D03*
X1645277Y127490D03*
G54D21*
X166785Y200472D03*
Y280472D03*
Y360472D03*
Y440472D03*
Y520472D03*
X243785Y200472D03*
Y280472D03*
Y360472D03*
Y440472D03*
Y520472D03*
X1488500Y200472D03*
Y280472D03*
Y360472D03*
Y440472D03*
Y520472D03*
X1565500Y200472D03*
Y280472D03*
Y360472D03*
Y440472D03*
Y520472D03*
G54D40*
X610129Y276000D03*
G54D31*
X434100Y176083D03*
Y220483D03*
X438100D03*
X607684Y252483D03*
X612684Y305483D03*
X616684D03*
X635184Y280483D03*
X680100Y252483D03*
X676100D03*
X672184D03*
X688184D03*
X684184D03*
X699684D03*
X1127100Y258483D03*
Y250483D03*
X1149600Y240983D03*
X1145600D03*
X1140100Y249483D03*
X1163000Y347483D03*
X1328100Y156483D03*
X1324100Y200883D03*
X1328100D03*
X1645277Y130457D03*
G54D22*
X166785Y230000D03*
Y310000D03*
Y390000D03*
Y470000D03*
Y550000D03*
X243785Y230000D03*
Y310000D03*
Y390000D03*
Y470000D03*
Y550000D03*
X1488500Y230000D03*
Y310000D03*
Y390000D03*
Y470000D03*
Y550000D03*
X1565500Y230000D03*
Y310000D03*
Y390000D03*
Y470000D03*
Y550000D03*
G36*
G01X41338Y17716D02*
G03X53150I5906J0D01*
G01Y23763D01*
G02X55572Y32155I15747J1D01*
G03X38916I-8328J5246D01*
G02X41338Y23763I-13327J-8392D01*
G01Y17716D01*
G37*
G36*
G01Y330708D02*
G03X53150I5906J0D01*
G01Y336755D01*
G02X55572Y345147I15747J1D01*
G03X38916I-8328J5246D01*
G02X41338Y336755I-13327J-8392D01*
G01Y330708D01*
G37*
G36*
G01X273622Y53148D02*
G03X285434I5906J0D01*
G01Y59195D01*
G02X287856Y67587I15747J1D01*
G03X271200I-8328J5246D01*
G02X273622Y59195I-13327J-8392D01*
G01Y53148D01*
G37*
G36*
G01X309055Y561023D02*
G03X320867I5906J0D01*
G01Y567070D01*
G02X323289Y575462I15747J1D01*
G03X306633I-8328J5246D01*
G02X309055Y567070I-13327J-8392D01*
G01Y561023D01*
G37*
G36*
G01X387796Y344488D02*
G03X399608I5906J0D01*
G01Y350535D01*
G02X402030Y358927I15747J1D01*
G03X385374I-8328J5246D01*
G02X387796Y350535I-13327J-8392D01*
G01Y344488D01*
G37*
G36*
G01X742126Y64961D02*
G03X753938I5906J0D01*
G01Y71008D01*
G02X756360Y79400I15747J1D01*
G03X739704I-8328J5246D01*
G02X742126Y71008I-13327J-8392D01*
G01Y64961D01*
G37*
G36*
G01Y344488D02*
G03X753938I5906J0D01*
G01Y350535D01*
G02X756360Y358927I15747J1D01*
G03X739704I-8328J5246D01*
G02X742126Y350535I-13327J-8392D01*
G01Y344488D01*
G37*
G36*
G01X978346Y64961D02*
G03X990158I5906J0D01*
G01Y71008D01*
G02X992580Y79400I15747J1D01*
G03X975924I-8328J5246D01*
G02X978346Y71008I-13327J-8392D01*
G01Y64961D01*
G37*
G36*
G01Y344488D02*
G03X990158I5906J0D01*
G01Y350535D01*
G02X992580Y358927I15747J1D01*
G03X975924I-8328J5246D01*
G02X978346Y350535I-13327J-8392D01*
G01Y344488D01*
G37*
G36*
G01X1332678D02*
G03X1344490I5906J0D01*
G01Y350535D01*
G02X1346912Y358927I15747J1D01*
G03X1330256I-8328J5246D01*
G02X1332678Y350535I-13327J-8392D01*
G01Y344488D01*
G37*
G36*
G01X1411418Y561023D02*
G03X1423230I5906J0D01*
G01Y567070D01*
G02X1425652Y575462I15747J1D01*
G03X1408996I-8328J5246D01*
G02X1411418Y567070I-13327J-8392D01*
G01Y561023D01*
G37*
G36*
G01X1446850Y53149D02*
G03X1458662I5906J0D01*
G01Y59196D01*
G02X1461084Y67588I15747J1D01*
G03X1444428I-8328J5246D01*
G02X1446850Y59196I-13327J-8392D01*
G01Y53149D01*
G37*
G36*
G01X1679134Y17716D02*
G03X1690946I5906J0D01*
G01Y23763D01*
G02X1693368Y32155I15747J1D01*
G03X1676712I-8328J5246D01*
G02X1679134Y23763I-13327J-8392D01*
G01Y17716D01*
G37*
G36*
G01Y330708D02*
G03X1690946I5906J0D01*
G01Y336755D01*
G02X1693368Y345147I15747J1D01*
G03X1676712I-8328J5246D01*
G02X1679134Y336755I-13327J-8392D01*
G01Y330708D01*
G37*
G36*
G01X1793306Y96457D02*
G03X1805118I5906J0D01*
G01Y102504D01*
G02X1807540Y110896I15747J1D01*
G03X1790884I-8328J5246D01*
G02X1793306Y102504I-13327J-8392D01*
G01Y96457D01*
G37*
G36*
G01Y478346D02*
G03X1805118I5906J0D01*
G01Y484393D01*
G02X1807540Y492785I15747J1D01*
G03X1790884I-8328J5246D01*
G02X1793306Y484393I-13327J-8392D01*
G01Y478346D01*
G37*
G54D14*
X47244Y27558D03*
Y340550D03*
X279528Y62990D03*
X314961Y570865D03*
X393702Y354330D03*
X748032Y74803D03*
Y354330D03*
X984252Y74803D03*
Y354330D03*
X1338584D03*
X1417324Y570865D03*
X1452756Y62991D03*
X1685040Y27558D03*
Y340550D03*
X1799212Y106299D03*
Y488188D03*
G54D32*
X428100Y178900D03*
Y170300D03*
Y223300D03*
Y214700D03*
X1334100Y158800D03*
Y150200D03*
Y203200D03*
Y194600D03*
G54D41*
X593198Y265173D03*
X620170D03*
Y286827D03*
X593198D03*
X1142114Y265173D03*
Y286827D03*
X1169086Y265173D03*
Y286827D03*
G54D50*
X683134Y267170D03*
Y269140D03*
Y271110D03*
Y273080D03*
Y275050D03*
Y277020D03*
Y278980D03*
Y280950D03*
Y282920D03*
Y284890D03*
Y286860D03*
Y288830D03*
X714234Y269140D03*
Y267170D03*
Y288830D03*
Y286860D03*
Y284890D03*
Y282920D03*
Y280950D03*
Y278980D03*
Y277020D03*
Y275050D03*
Y273080D03*
Y271110D03*
X1048050Y263170D03*
Y265140D03*
Y267110D03*
Y269080D03*
Y271050D03*
Y273020D03*
Y274980D03*
Y276950D03*
Y278920D03*
Y280890D03*
Y282860D03*
Y284830D03*
X1079150Y269080D03*
Y267110D03*
Y265140D03*
Y263170D03*
Y284830D03*
Y282860D03*
Y280890D03*
Y278920D03*
Y276950D03*
Y274980D03*
Y273020D03*
Y271050D03*
G54D23*
X207874Y639095D03*
X1524409D03*
G54D42*
X595857Y262514D03*
X617511D03*
Y289486D03*
X595857D03*
X1144773Y262514D03*
Y289486D03*
X1166427Y262514D03*
Y289486D03*
G54D33*
X422000Y169925D03*
Y173075D03*
Y214425D03*
Y217575D03*
X1340100Y150125D03*
Y153275D03*
X1340600Y194325D03*
Y197475D03*
G54D51*
X709514Y264420D03*
X707544D03*
X705574D03*
X703604D03*
X697704D03*
X695734D03*
X693764D03*
X691794D03*
X689824D03*
X687854D03*
X685884D03*
Y291580D03*
X687854D03*
X689824D03*
X691794D03*
X693764D03*
X695734D03*
X697704D03*
X703604D03*
X705574D03*
X707544D03*
X709514D03*
X711484Y264420D03*
Y291580D03*
X1072460Y260420D03*
X1070490D03*
X1068520D03*
X1066550D03*
X1064580D03*
X1058680D03*
X1056710D03*
X1054740D03*
X1052770D03*
X1050800D03*
Y287580D03*
X1052770D03*
X1054740D03*
X1056710D03*
X1058680D03*
X1064580D03*
X1066550D03*
X1068520D03*
X1070490D03*
X1072460D03*
X1076400Y260420D03*
X1074430D03*
Y287580D03*
X1076400D03*
G54D60*
X822087Y200984D03*
X940197D03*
G54D24*
X240866Y15512D03*
X300866Y10197D03*
X1431417Y15512D03*
X1491417Y10197D03*
G54D15*
X45275Y236614D03*
Y411594D03*
X72835Y236614D03*
X68898Y226771D03*
X59055Y222834D03*
X49212Y226771D03*
X68898Y246457D03*
X49212D03*
X59055Y250394D03*
X68898Y421437D03*
X72835Y411594D03*
X68898Y401751D03*
X59055Y397814D03*
X49212Y401751D03*
Y421437D03*
X59055Y425374D03*
X1673228Y222834D03*
X1663385Y226771D03*
X1659448Y236614D03*
X1663385Y246457D03*
X1673228Y250394D03*
Y397834D03*
X1663385Y401771D03*
X1659448Y411614D03*
X1663385Y421457D03*
X1673228Y425394D03*
X1687008Y236614D03*
X1683071Y226771D03*
Y246457D03*
Y421457D03*
X1687008Y411614D03*
X1683071Y401771D03*
G54D16*
X59055Y236614D03*
Y411594D03*
X1673228Y236614D03*
Y411614D03*
G54D34*
X601340Y235000D03*
X593860D03*
X664924Y233500D03*
X657444D03*
X720444Y305000D03*
X727924D03*
X1041840Y247000D03*
X1034360D03*
X1074260Y360500D03*
X1096860Y312000D03*
X1104340D03*
X1081740Y360500D03*
X1166860Y312000D03*
X1174340D03*
X1166860Y303000D03*
X1174340D03*
G54D70*
X1848583Y99212D03*
X1848582Y481693D03*
G54D43*
X603731Y262614D03*
X605700D03*
X607668D03*
X609637D03*
X611605D03*
X613574D03*
X615542D03*
Y289386D03*
X613574D03*
X611605D03*
X609637D03*
X607668D03*
X605700D03*
X603731D03*
X1146742Y262614D03*
X1148710D03*
X1150679D03*
X1152647D03*
X1154616D03*
X1156584D03*
X1158553D03*
Y289386D03*
X1156584D03*
X1154616D03*
X1152647D03*
X1150679D03*
X1148710D03*
X1146742D03*
G54D61*
X825900Y362200D03*
X866400Y382200D03*
X906900Y362200D03*
G54D25*
X287402Y628465D03*
X263780Y659961D03*
X668314Y570042D03*
X681498Y575042D03*
Y565042D03*
X668420Y598187D03*
X681604Y593187D03*
Y603187D03*
X1011017Y570042D03*
X997833Y575042D03*
Y565042D03*
X1011017Y598187D03*
X997833Y593187D03*
Y603187D03*
X1468504Y628465D03*
X1444882Y659961D03*
G54D52*
X704794Y278000D03*
X1057490Y274000D03*
G54D80*
G01X417600Y213500D02*
X417500Y213600D01*
G01X605800Y256500D02*
Y256600D01*
X607259Y258059D01*
X607668Y259047D01*
Y262614D01*
G01X616666Y239161D02*
X620600D01*
G01X609637Y262614D02*
Y254523D01*
G01D02*
X609632D01*
X607684Y252575D01*
G01X616666Y241720D02*
X613973D01*
X612772Y242921D01*
Y247920D01*
X614307Y249455D01*
X626770D01*
X629386Y246839D01*
X640702D01*
G01X605700Y262614D02*
Y259500D01*
G01X613574Y289386D02*
Y296110D01*
X612684Y297000D01*
G01D02*
Y302425D01*
G01X616684D02*
Y294500D01*
G01D02*
X615542Y293358D01*
Y289386D01*
G01X602928Y293969D02*
Y293397D01*
X605700Y290625D01*
Y289386D01*
G01X608259Y302500D02*
Y297841D01*
X611605Y294495D01*
Y289386D01*
G01X600875Y295937D02*
Y292808D01*
X603731Y289952D01*
Y289386D01*
G01X612684Y302425D02*
X612383D01*
X610244Y304564D01*
Y308485D01*
X612684Y310925D01*
G01X616684Y302425D02*
X616985D01*
X619124Y304564D01*
Y308485D01*
X616684Y310925D01*
G01X608259Y302500D02*
Y305000D01*
G01X638259Y260000D02*
Y264500D01*
G01D02*
X640684D01*
G01X640702Y244280D02*
X643820D01*
X645900Y242200D01*
G01X626026Y266657D02*
X623573Y269110D01*
X620070D01*
G01X635109Y264500D02*
X628183D01*
X626026Y266657D01*
G01X620070Y267142D02*
X622042D01*
X629184Y260000D01*
X629684D01*
G01D02*
X635109D01*
G01X640702Y246839D02*
X644502D01*
G01X630684Y269000D02*
X627684D01*
X625605Y271079D01*
X620070D01*
G01X623684Y281000D02*
X621637Y278953D01*
X620070D01*
G01X638259Y269000D02*
X640684D01*
G01X635184Y277425D02*
X639034D01*
X639109Y277500D01*
G01X635184Y277425D02*
X635109Y277500D01*
X629018D01*
G01D02*
X626517D01*
X624033Y275016D01*
X620070D01*
G01X635109Y273500D02*
X627090D01*
X627089Y273499D01*
X625684D01*
G01D02*
X625232Y273047D01*
X620070D01*
G01X620170Y286827D02*
X620649D01*
X622003Y288181D01*
Y297500D01*
G01D02*
Y300504D01*
X622184Y300685D01*
Y302425D01*
G01X627184Y287500D02*
X622574Y282890D01*
X620070D01*
G01X635109Y288500D02*
X628184D01*
X627184Y287500D01*
G01X639609Y298000D02*
X636609D01*
X635184Y296575D01*
G01X629684Y300000D02*
Y298500D01*
X631609Y296575D01*
X635184D01*
G01X627684Y293425D02*
X627609D01*
X624184Y290000D01*
Y287703D01*
X621339Y284858D01*
X620070D01*
G01X635184Y293425D02*
X627684D01*
G01X635184D02*
X639534D01*
X639609Y293500D01*
G01X620070Y276984D02*
X623093D01*
X628109Y282000D01*
G01D02*
Y282301D01*
X630308Y284500D01*
G01D02*
X635109D01*
G01Y269000D02*
X630684D01*
G01X635184Y301425D02*
X631109D01*
X629684Y300000D01*
G01X641525Y308500D02*
Y304741D01*
X640284Y303500D01*
G01X635184Y304575D02*
Y309000D01*
X635600Y309416D01*
G01D02*
X636516Y308500D01*
X641525D01*
G01X676638Y230894D02*
X673684Y227940D01*
Y224240D01*
G01X676100Y252575D02*
X680100D01*
G01D02*
Y256416D01*
X683592Y259908D01*
G01X672184Y252575D02*
Y253000D01*
X676756Y257572D01*
G01D02*
X678072D01*
X683000Y262500D01*
X685204D01*
X685884Y263180D01*
Y264420D01*
G01X683134Y269140D02*
X679324D01*
X677184Y267000D01*
G01X668609Y269000D02*
X666259D01*
X664259Y267000D01*
G01X677184D02*
X676685Y266501D01*
X669880D01*
X668609Y267772D01*
Y269000D01*
G01X683134Y278980D02*
X679184D01*
G01X673684Y280950D02*
Y280916D01*
X677580Y277020D01*
X683134D01*
G01Y280950D02*
X676684D01*
G01X664609Y296500D02*
Y292500D01*
G01X667759Y288500D02*
X670184D01*
G01X664609Y292500D02*
X667759Y289350D01*
Y288500D01*
G01X664609Y280500D02*
X662184D01*
G01X680100Y297600D02*
Y290084D01*
X681354Y288830D01*
X683134D01*
G01X680100Y297600D02*
X672500D01*
X669600Y300500D01*
X667675D01*
G01X679184Y273190D02*
X680994D01*
X681104Y273080D01*
X683134D01*
G01X672242Y294442D02*
X670184Y296500D01*
X667759D01*
G01X672242Y294442D02*
X674062D01*
X676642Y291862D01*
Y290042D01*
X679824Y286860D01*
X683134D01*
G01Y275050D02*
X677234D01*
X676184Y274000D01*
G01X673800Y289400D02*
X672284D01*
X669184Y292500D01*
X667759D01*
G01X673800Y289400D02*
Y287884D01*
X676794Y284890D01*
X683134D01*
G01X667759Y280500D02*
Y284500D01*
G01D02*
X671400D01*
X672200Y283700D01*
G01D02*
X673999D01*
X674779Y282920D01*
X683134D01*
G01X664525Y304500D02*
X662100D01*
G01X667675D02*
Y308500D01*
G01Y304500D02*
X670600D01*
X674600Y300500D01*
X686354D01*
X687854Y299000D01*
G01X702223Y197419D02*
Y198434D01*
X701545Y199112D01*
Y208472D01*
X705073Y212000D01*
X707425D01*
G01X708600Y189260D02*
X713976D01*
X715236Y188000D01*
X720100D01*
G01X704240Y185000D02*
X704340D01*
X708600Y189260D01*
G01X710575Y208000D02*
Y206268D01*
X710000Y205693D01*
Y203000D01*
G01X708600Y196740D02*
Y201600D01*
X710000Y203000D01*
G01X689684Y224240D02*
Y230762D01*
G01X681684Y224240D02*
Y230820D01*
G01X683592Y259908D02*
X686251D01*
X687854Y261511D01*
Y264420D01*
G01X688945Y259761D02*
X689824Y260640D01*
Y264420D01*
G01X698497Y257727D02*
Y257875D01*
X697704Y258668D01*
Y264420D01*
G01X699684Y252575D02*
X698497Y253762D01*
Y257727D01*
G01X684184Y252575D02*
X688184D01*
G01D02*
Y256136D01*
X691794Y259746D01*
Y261073D01*
G01D02*
Y264420D01*
G01X695734Y296950D02*
Y301475D01*
X696259Y302000D01*
G01X695734Y291580D02*
Y296950D01*
G01X685884Y291580D02*
Y297000D01*
G01X687854Y299000D02*
Y291580D01*
G01X693764D02*
Y294921D01*
X693109Y295576D01*
Y302000D01*
G01X696259D02*
Y305150D01*
X697609Y306500D01*
G01D02*
Y311185D01*
X699184Y312760D01*
G01X693109Y302000D02*
Y305150D01*
X691759Y306500D01*
G01D02*
Y309000D01*
G01D02*
Y311185D01*
X690184Y312760D01*
G01X997833Y565042D02*
X703029D01*
X702349Y565722D01*
Y574362D01*
X703029Y575042D01*
X997833D01*
G01X710575Y208000D02*
Y212000D01*
G01D02*
Y214075D01*
X712000Y215500D01*
G01X717384Y273400D02*
X715734Y275050D01*
X714234D01*
G01Y278980D02*
X719484D01*
G01X725000Y292500D02*
X729000Y296500D01*
Y301000D01*
X727924Y302076D01*
Y305000D01*
G01X713184D02*
Y298500D01*
G01D02*
X714770D01*
X720444Y304174D01*
Y305000D01*
G01X862600Y29500D02*
X865220Y32120D01*
Y344678D01*
X882666Y362124D01*
Y378401D01*
X885265Y381000D01*
G01X894500Y396500D02*
X890200Y392200D01*
Y354200D01*
X872533Y336533D01*
Y29432D01*
G01X882660Y350840D02*
X869100Y337280D01*
Y30000D01*
X867100Y28000D01*
G01X885100Y361500D02*
X867100Y343500D01*
Y31500D01*
G01X887500Y355680D02*
X882660Y350840D01*
G01X1047163Y197437D02*
X1037100Y207500D01*
Y218000D01*
X1021120Y233980D01*
Y344221D01*
X1023492Y346593D01*
G01X1034537Y201437D02*
Y217904D01*
X1019240Y233201D01*
Y353805D01*
X1021414Y355979D01*
G01X1013000Y188000D02*
X1017100D01*
X1018860Y189760D01*
X1024600D01*
G01D02*
Y185000D01*
G01X1023200Y203500D02*
Y207175D01*
X1024525Y208500D01*
G01X1024600Y197240D02*
Y202100D01*
X1023200Y203500D01*
G01X1027675Y212500D02*
Y215000D01*
G01X1024525Y208500D02*
Y212500D01*
G01D02*
Y215000D01*
G01X1034360Y247000D02*
Y254000D01*
G01X1041840Y247000D02*
Y253760D01*
G01X1049100Y247000D02*
Y252500D01*
X1047840Y253760D01*
X1041840D01*
G01X1048050Y273020D02*
X1042800D01*
G01X1017300Y322500D02*
Y385600D01*
G01X1066550Y260420D02*
Y255050D01*
G01D02*
Y250525D01*
X1066025Y250000D01*
G01D02*
Y246850D01*
X1064675Y245500D01*
G01X1063100Y239240D02*
X1064675Y240815D01*
Y245500D01*
G01X1068520Y260420D02*
Y257079D01*
X1069175Y256424D01*
Y250000D01*
G01D02*
Y246850D01*
X1070525Y245500D01*
G01D02*
Y243000D01*
G01D02*
Y240815D01*
X1072100Y239240D01*
G01X1044900Y278600D02*
X1046550Y276950D01*
X1048050D01*
G01X1070490Y290927D02*
Y287580D01*
G01Y290927D02*
Y292254D01*
X1072286Y294050D01*
Y294922D01*
G01D02*
X1074100Y296736D01*
Y299425D01*
G01X1062600D02*
Y296390D01*
X1064032Y294958D01*
G01D02*
X1064580Y294410D01*
Y287580D01*
G01X1073339Y292239D02*
X1072460Y291360D01*
Y287580D01*
G01X1072600Y327760D02*
Y324000D01*
G01X1064600Y327760D02*
Y324000D01*
G01X1097675Y255500D02*
Y259500D01*
G01X1094525Y263500D02*
X1092100D01*
G01X1097675Y259500D02*
X1094525Y262650D01*
Y263500D01*
G01X1097675Y247500D02*
X1100100D01*
G01X1094525Y243500D02*
Y247500D01*
G01X1076400Y260420D02*
Y255200D01*
X1078100Y253500D01*
G01D02*
X1086600D01*
X1092600Y247500D01*
X1094525D01*
G01X1079150Y263170D02*
X1080930D01*
X1082100Y262000D01*
Y257500D01*
X1082850Y256750D01*
G01D02*
X1087350D01*
X1092600Y251500D01*
X1094525D01*
G01X1074430Y260420D02*
Y256461D01*
G01X1086850Y265750D02*
X1085490Y267110D01*
X1079150D01*
G01X1094525Y259500D02*
X1093100D01*
X1086850Y265750D01*
G01X1079150Y265140D02*
X1082460D01*
X1087100Y260500D01*
G01X1094525Y255500D02*
X1090385Y257215D01*
X1087100Y260500D01*
G01X1094525Y271500D02*
Y267500D01*
G01X1089937Y271255D02*
Y268564D01*
X1091001Y267500D01*
X1094525D01*
G01X1079150Y271050D02*
X1085600D01*
G01X1101500Y271500D02*
Y274000D01*
X1100431Y275069D01*
X1098569D01*
X1097675Y274175D01*
Y271500D01*
G01X1079150Y273020D02*
X1083100D01*
G01X1079150Y274980D02*
X1088079D01*
G01X1080600Y294000D02*
X1082100Y295500D01*
Y299425D01*
G01X1074430Y287580D02*
Y290330D01*
X1077300Y293200D01*
Y294000D01*
G01D02*
X1080600D01*
G01X1079150Y282860D02*
X1082960D01*
X1085100Y285000D01*
G01D02*
X1091675D01*
X1093675Y283000D01*
G01X1098025Y285000D02*
X1096025Y283000D01*
X1093675D01*
G01X1083100Y278810D02*
X1081290D01*
X1081180Y278920D01*
X1079150D01*
G01Y276950D02*
X1085050D01*
X1086100Y278000D01*
G01X1090100Y299425D02*
Y299000D01*
X1085528Y294428D01*
G01D02*
X1083100Y292000D01*
X1078600D01*
X1076400Y289800D01*
Y287580D01*
G01X1079150Y269080D02*
X1087762D01*
X1089937Y271255D01*
G01X1082100Y299425D02*
X1086100D01*
G01X1080600Y324000D02*
Y327760D01*
G01X1078100Y299425D02*
X1074100D01*
G01X1101200Y355600D02*
X1107000D01*
G01X1094500D02*
X1101200D01*
G01X1081740Y360500D02*
X1089600D01*
X1094500Y355600D01*
G01X1142214Y273047D02*
X1140647D01*
X1133000Y265400D01*
X1129800D01*
G01X1131700Y263000D02*
X1133600D01*
X1139710Y269110D01*
X1142214D01*
G01X1127175Y263500D02*
X1127675Y263000D01*
X1131700D01*
G01X1127100Y247425D02*
Y242500D01*
G01D02*
X1121675D01*
X1120675Y243500D01*
G01D02*
Y247175D01*
X1122000Y248500D01*
G01X1122675Y254000D02*
X1125675D01*
X1127100Y255425D01*
G01Y250575D02*
X1131175D01*
X1132600Y252000D01*
G01D02*
Y253500D01*
X1130675Y255425D01*
X1127100D01*
G01Y258575D02*
X1122750D01*
X1122675Y258500D01*
G01X1127100Y258575D02*
X1134600D01*
G01X1134175Y270000D02*
Y269699D01*
X1131976Y267500D01*
G01D02*
X1127175D01*
G01X1124025Y287500D02*
X1121600D01*
G01X1124025Y292000D02*
Y287500D01*
G01Y283000D02*
X1121600D01*
G01X1127175Y287500D02*
X1134101D01*
X1136258Y285343D01*
G01X1132600Y292000D02*
X1127175D01*
G01X1142214Y284858D02*
X1140242D01*
X1133100Y292000D01*
X1132600D01*
G01X1127175Y278500D02*
X1132231D01*
X1133459Y277272D01*
G01D02*
X1134319D01*
X1136000Y278953D01*
G01X1142214Y276984D02*
X1138251D01*
X1135767Y274500D01*
X1132113D01*
G01X1127100Y274575D02*
X1123250D01*
X1123175Y274500D01*
G01X1132113D02*
X1127175D01*
X1127100Y274575D01*
G01X1127175Y283000D02*
X1131600D01*
G01X1142214Y280921D02*
X1136679D01*
X1134600Y283000D01*
X1131600D01*
G01X1121582Y305161D02*
X1130087D01*
X1130100Y305174D01*
G01D02*
X1130113Y305161D01*
X1133019D01*
X1135593Y302587D01*
X1147282D01*
X1149019Y304324D01*
Y308557D01*
X1147296Y310280D01*
X1145618D01*
G01X1121582Y307720D02*
X1130510D01*
G01X1118776Y362500D02*
X1122100D01*
X1123400Y361200D01*
Y356300D01*
G01X1107000Y355600D02*
X1109175D01*
X1112500Y358925D01*
G01D02*
X1115076D01*
X1115241Y358760D01*
X1118776D01*
G01X1128224Y366240D02*
X1131240D01*
X1132000Y367000D01*
G01X1145600Y249575D02*
X1145299D01*
X1143160Y247436D01*
Y243515D01*
X1145600Y241075D01*
G01Y249575D02*
Y257500D01*
G01X1146742Y262614D02*
Y258642D01*
X1145600Y257500D01*
G01X1149600Y249575D02*
X1152040Y247135D01*
Y243515D01*
X1149600Y241075D01*
G01Y249575D02*
Y255000D01*
G01X1148710Y262614D02*
Y255890D01*
X1149600Y255000D01*
G01X1156584Y262614D02*
Y261264D01*
X1160990Y256858D01*
Y252134D01*
G01X1140100Y249575D02*
Y254500D01*
G01X1142114Y265173D02*
X1141635D01*
X1140100Y263638D01*
Y254500D01*
G01X1142214Y267142D02*
X1140945D01*
X1138100Y264297D01*
Y262000D01*
X1134675Y258575D01*
X1134600D01*
G01X1158553Y262614D02*
Y261954D01*
X1163266Y257241D01*
Y255311D01*
G01X1156584Y289386D02*
Y292488D01*
G01X1154616Y289386D02*
Y293503D01*
X1156509Y295396D01*
G01X1142214Y282890D02*
X1138711D01*
X1136258Y285343D01*
G01X1154600Y299425D02*
Y297053D01*
X1152647Y295100D01*
Y294655D01*
G01D02*
Y289386D01*
G01X1142214Y275016D02*
X1139191D01*
X1134175Y270000D01*
G01X1142214Y278953D02*
X1136000D01*
G01X1145618Y312839D02*
X1141600D01*
G01X1153500Y342500D02*
X1151500Y340500D01*
X1150260D01*
G01X1157740Y343059D02*
X1161634D01*
X1163000Y344425D01*
G01X1168500D02*
X1163000D01*
G01X1179500Y350000D02*
Y348000D01*
X1175925Y344425D01*
X1168500D01*
G01X1176059Y361260D02*
Y356634D01*
X1176000Y356575D01*
G01X1179500Y355000D02*
X1177925Y356575D01*
X1176000D01*
G01X1178900Y359620D02*
Y361800D01*
X1173500Y367200D01*
Y368740D01*
G01X1465197Y8012D02*
Y13097D01*
X1473313Y21213D01*
Y27313D01*
X1498180Y52180D01*
Y63500D01*
G01X1465197Y18012D02*
X1466940Y19755D01*
Y27940D01*
X1491500Y52500D01*
Y65228D01*
X1490228Y66500D01*
G01X1505100Y64500D02*
X1504100D01*
X1500674Y61074D01*
Y51174D01*
X1477000Y27500D01*
Y20616D01*
X1478313Y19303D01*
Y16721D01*
X1474604Y13012D01*
X1470197D01*
G01Y23012D02*
Y27697D01*
X1494000Y51500D01*
Y59500D01*
G01D02*
Y65772D01*
X1494728Y66500D01*
G01X1641077Y127429D02*
X1636400D01*
G01X1644917Y124581D02*
X1644098Y125400D01*
X1638429D01*
X1636400Y127429D01*
G01X1641077Y130579D02*
Y132914D01*
X1643217Y135054D01*
G01X1645277Y130549D02*
Y132994D01*
X1643217Y135054D01*
G01X1630075Y142500D02*
X1630083Y142492D01*
Y139008D01*
X1630075Y139000D01*
G01X1643500Y147807D02*
X1640307D01*
X1635000Y142500D01*
G01D02*
X1630075D01*
G01Y146000D02*
X1629984Y146091D01*
Y147675D01*
X1629983Y147676D01*
Y149408D01*
X1630075Y149500D01*
G01X1643500Y150366D02*
X1637366D01*
X1634500Y147500D01*
G01D02*
X1633000Y146000D01*
X1630075D01*
G01X1647500Y140000D02*
X1649500Y138000D01*
X1652425D01*
G01X1647500Y140000D02*
Y143500D01*
X1645752Y145248D01*
X1643500D01*
G01X1630075Y158000D02*
Y153500D01*
G01Y158000D02*
X1634001D01*
X1639076Y152925D01*
X1643500D01*
G01X1626925Y153500D02*
Y156000D01*
G01X1641500Y178000D02*
X1639000Y175500D01*
Y167500D01*
X1640779Y165721D01*
X1643500D01*
G01X1658500Y183000D02*
X1655500Y180000D01*
Y173341D01*
X1650439Y168280D01*
X1643500D01*
G01X1652500Y185000D02*
Y173000D01*
X1650339Y170839D01*
X1643500D01*
G01X1658000Y179500D02*
Y165341D01*
X1648143Y155484D01*
X1643500D01*
G01X1629000Y175000D02*
Y166499D01*
X1637456Y158043D01*
X1643500D01*
G01X1635000Y164500D02*
X1638897Y160603D01*
X1643500D01*
G01X1642000Y184500D02*
X1639500D01*
X1632500Y177500D01*
Y167000D01*
X1635000Y164500D01*
G01X1645000Y184500D02*
X1642500Y182000D01*
X1640000D01*
X1634500Y176500D01*
Y168500D01*
X1639838Y163162D01*
X1643500D01*
G01X1673000Y141000D02*
X1670500Y143500D01*
Y146500D01*
X1669193Y147807D01*
X1666500D01*
G01X1673000Y141000D02*
X1675001D01*
X1675501Y141500D01*
X1677925D01*
G01X1666500Y150366D02*
X1670134D01*
X1673000Y147500D01*
Y146500D01*
G01D02*
X1674000Y145500D01*
X1677925D01*
G01X1673250Y151750D02*
X1672075Y152925D01*
X1666500D01*
G01X1677925Y153500D02*
Y149500D01*
G01X1673250Y151750D02*
X1675500Y149500D01*
X1677925D01*
G01X1677500Y182000D02*
X1668898Y173398D01*
X1666500D01*
G01Y170839D02*
X1670339D01*
X1674500Y175000D01*
G01X1680000D02*
X1678000D01*
X1671280Y168280D01*
X1666500D01*
G01Y178500D02*
X1662000Y174000D01*
Y166721D01*
X1663000Y165721D01*
X1666500D01*
G01X1677000Y169500D02*
X1670662Y163162D01*
X1666500D01*
G01X1680500Y165000D02*
X1675999D01*
X1671602Y160603D01*
X1666500D01*
G01X1661000Y178500D02*
X1660000Y177500D01*
Y160500D01*
X1662457Y158043D01*
X1666500D01*
G01X1682000Y160000D02*
X1680000D01*
X1677500Y157500D01*
X1675000D01*
X1672984Y155484D01*
X1666500D01*
G01X1692000Y76570D02*
Y94450D01*
X1707500Y109950D01*
Y132341D01*
X1701000Y138841D01*
Y159000D01*
G01Y164500D02*
X1702960Y162540D01*
Y139540D01*
X1709500Y133000D01*
Y107000D01*
X1695500Y93000D01*
Y76500D01*
G01X1702600Y171500D02*
X1701600Y172500D01*
X1696000D01*
X1693720Y170220D01*
Y143945D01*
X1690275Y140500D01*
X1682075D01*
X1681075Y141500D01*
G01Y145500D02*
X1683795Y142780D01*
X1689330D01*
X1691000Y144450D01*
Y177000D01*
X1697000Y183000D01*
X1700100D01*
X1701100Y182000D01*
G01X1721600Y194760D02*
X1723600Y192760D01*
Y179000D01*
X1721700Y177100D01*
X1717401D01*
X1704840Y164539D01*
Y140760D01*
X1705100Y140500D01*
G01X1721600Y198500D02*
X1725480Y194620D01*
Y176539D01*
X1720591Y171650D01*
X1714650D01*
X1706720Y163720D01*
Y142880D01*
X1707100Y142500D01*
G01X1685000Y133000D02*
X1690000Y138000D01*
X1691000D01*
X1696000Y143000D01*
Y165500D01*
X1697000Y166500D01*
X1702000D01*
X1718000Y182500D01*
Y199500D01*
X1720500Y202000D01*
X1742500D01*
X1744500Y200000D01*
X1752342D01*
X1758824Y193518D01*
Y191240D01*
G01X1738000Y124500D02*
X1763500Y99000D01*
X1775599D01*
X1780000Y103401D01*
Y126500D01*
X1805660Y152160D01*
Y186059D01*
X1818600Y198999D01*
Y301501D01*
X1836312Y319213D01*
X1843957D01*
G01X1837164Y419238D02*
X1832100Y414174D01*
Y347500D01*
X1800700Y316100D01*
Y207675D01*
X1790760Y197735D01*
Y183460D01*
X1778781Y171481D01*
X1768281D01*
X1763800Y167000D01*
X1726000D01*
X1719700Y160700D01*
Y155901D01*
X1721000Y154601D01*
Y142525D01*
G01X1735925Y181000D02*
X1731000Y176075D01*
Y173500D01*
X1727500Y170000D01*
X1725000D01*
X1715500Y160500D01*
Y156500D01*
X1717500Y154500D01*
Y142001D01*
X1723721Y135780D01*
X1759220D01*
X1765500Y129500D01*
X1773500D01*
G01X1772975Y124500D02*
X1766999D01*
X1757999Y133500D01*
X1718600D01*
X1709600Y142500D01*
Y158000D01*
G01X1715525Y153000D02*
X1713100Y155425D01*
Y166075D01*
X1715525Y168500D01*
G01X1722063Y156962D02*
X1726801Y161700D01*
X1760601D01*
X1762901Y164000D01*
X1774525D01*
X1793040Y182515D01*
Y196790D01*
X1802980Y206730D01*
Y315155D01*
X1834380Y346555D01*
Y411454D01*
X1842164Y419238D01*
G01X1735925Y186500D02*
Y193925D01*
X1740000Y198000D01*
X1742500D01*
G01X1852164Y419238D02*
Y416618D01*
X1838940Y403394D01*
Y344665D01*
X1807540Y313265D01*
Y204840D01*
X1797600Y194900D01*
Y180001D01*
X1786519Y168920D01*
Y166082D01*
X1790119Y162482D01*
Y161520D01*
X1789115Y160516D01*
X1788153D01*
X1784553Y164116D01*
X1783591D01*
X1782587Y163112D01*
Y162150D01*
X1786187Y158550D01*
Y157588D01*
X1785183Y156584D01*
X1784221D01*
X1780621Y160184D01*
X1779659D01*
X1778655Y159180D01*
Y158218D01*
X1782255Y154618D01*
Y153656D01*
X1781251Y152652D01*
X1780289D01*
X1776689Y156252D01*
X1775587D01*
X1764000Y144665D01*
Y142525D01*
G01X1847164Y419238D02*
Y415164D01*
X1836660Y404660D01*
Y345610D01*
X1805260Y314210D01*
Y205785D01*
X1795320Y195845D01*
Y181570D01*
X1775250Y161500D01*
X1767475D01*
X1764000Y158025D01*
G01X1742500Y198000D02*
X1750563D01*
G01X1747925Y204000D02*
X1751001D01*
X1757001Y198000D01*
X1785107D01*
X1796540Y209433D01*
Y267780D01*
X1789040Y275280D01*
Y354060D01*
X1784100Y359000D01*
X1776600D01*
X1767600Y350000D01*
G01X1739075Y181000D02*
X1743500D01*
G01D02*
X1745999D01*
X1748759Y183760D01*
X1749376D01*
G01X1739075Y186500D02*
X1740075Y187500D01*
X1743500D01*
G01D02*
X1749376D01*
G01X1773500Y129500D02*
X1778000D01*
X1803380Y154880D01*
Y193780D01*
X1812100Y202500D01*
Y308600D01*
X1838500Y335000D01*
X1848170D01*
X1848957Y334213D01*
G01X1800100Y187500D02*
Y194001D01*
X1809820Y203721D01*
Y309545D01*
X1839488Y339213D01*
X1843957D01*
G01X1817500Y188000D02*
X1823600Y194100D01*
Y299924D01*
X1831676Y308000D01*
X1859600D01*
X1864600Y313000D01*
Y326500D01*
X1861887Y329213D01*
X1853957D01*
G01X1809600Y195000D02*
X1816320Y201720D01*
Y302446D01*
X1838087Y324213D01*
X1848957D01*
G01X1811500Y186000D02*
X1821720Y196220D01*
Y300703D01*
X1830897Y309880D01*
X1851500D01*
X1853957Y312337D01*
Y319213D01*
G01Y349213D02*
X1853162D01*
X1846820Y355555D01*
Y405945D01*
X1856320Y415445D01*
Y418187D01*
X1842169Y432338D01*
X1842164D01*
G01X1858957Y344213D02*
Y349715D01*
X1855569Y353103D01*
X1852497D01*
X1849100Y356500D01*
Y392011D01*
X1849780Y392691D01*
X1857201D01*
X1857881Y393371D01*
Y394791D01*
X1857201Y395471D01*
X1849780D01*
X1849100Y396151D01*
Y397571D01*
X1849780Y398251D01*
X1857201D01*
X1857881Y398931D01*
Y400351D01*
X1857201Y401031D01*
X1849780D01*
X1849100Y401711D01*
Y405000D01*
X1858600Y414500D01*
Y419132D01*
X1847164Y430568D01*
G01X1852164Y435538D02*
X1867000Y420702D01*
Y342256D01*
X1858957Y334213D01*
G01X1837164Y428238D02*
X1837100Y428302D01*
Y432500D01*
X1839600Y435000D01*
X1843879D01*
X1851085Y432015D01*
X1864500Y418600D01*
Y343901D01*
X1859812Y339213D01*
X1853957D01*
G54D35*
X607684Y237850D03*
G54D26*
X406600Y169500D03*
Y214000D03*
X412400Y169500D03*
X415200Y180100D03*
X421000D03*
X412400Y214000D03*
X415200Y224500D03*
X421000D03*
X640284Y303500D03*
X646084D03*
X671084Y274000D03*
X665284D03*
X710000Y203000D03*
X704200D03*
X1023200Y203500D03*
X1029000D03*
X1091200Y278000D03*
X1097000D03*
X1122000Y248500D03*
X1116200D03*
X1341200Y160300D03*
Y204400D03*
X1347000Y160300D03*
X1349600Y149500D03*
X1355400D03*
X1347000Y204400D03*
X1349600Y194000D03*
X1355400D03*
G54D53*
X706184Y305000D03*
X713184D03*
X1056100Y247000D03*
X1049100D03*
X1629737Y96334D03*
X1636737D03*
G54D44*
X620070Y267142D03*
Y269110D03*
X593298D03*
Y267142D03*
X620070Y271079D03*
Y273047D03*
Y275016D03*
Y276984D03*
Y278953D03*
Y280921D03*
Y282890D03*
Y284858D03*
X593298D03*
Y282890D03*
Y280921D03*
Y278953D03*
Y276984D03*
X1142214Y269110D03*
Y267142D03*
Y284858D03*
Y282890D03*
Y280921D03*
Y278953D03*
Y276984D03*
Y275016D03*
Y273047D03*
Y271079D03*
X1168986Y267142D03*
Y269110D03*
Y271079D03*
Y273047D03*
Y275016D03*
Y282890D03*
Y284858D03*
G54D17*
X102422Y604336D03*
X590000Y208500D03*
X1286300Y331400D03*
X1717750Y599624D03*
G54D62*
X825900Y382200D03*
Y372200D03*
X866400Y362200D03*
Y372200D03*
X906900Y382200D03*
Y372200D03*
G54D71*
X1835739Y99212D03*
X1835738Y481693D03*
G54D45*
X606484Y312500D03*
X594884D03*
X623384Y231000D03*
X634984D03*
X695800Y242000D03*
X707400D03*
X1127300Y321000D03*
X1155800Y239500D03*
X1138900Y321000D03*
X1167400Y239500D03*
G54D27*
X417000Y164900D03*
Y159100D03*
X417500Y169600D03*
Y175400D03*
Y208900D03*
Y203100D03*
Y213600D03*
Y219400D03*
X607684Y234050D03*
X1107000Y355600D03*
Y361400D03*
X1154600Y317950D03*
X1345000Y144900D03*
Y139100D03*
X1344800Y149800D03*
Y155600D03*
X1344500Y188900D03*
Y183100D03*
X1344800Y193700D03*
Y199500D03*
G54D36*
X616666Y239161D03*
Y246839D03*
Y244280D03*
Y241720D03*
X640702Y239161D03*
Y246839D03*
Y244280D03*
Y241720D03*
X1121582Y305161D03*
Y307720D03*
Y310280D03*
Y312839D03*
X1145618Y305161D03*
Y307720D03*
Y310280D03*
Y312839D03*
G54D54*
X739600Y140094D03*
Y176906D03*
X994000Y140094D03*
Y176906D03*
G54D63*
X1128224Y358760D03*
X1118776D03*
X1128224Y366240D03*
X1118776D03*
Y362500D03*
X1758824Y183760D03*
Y191240D03*
X1749376D03*
Y187500D03*
Y183760D03*
G54D18*
X137355Y120500D03*
X134600Y150000D03*
Y134000D03*
X156785Y101285D03*
X205061Y67500D03*
X211425Y106075D03*
X205061Y93000D03*
X200600Y109059D03*
X210925Y115575D03*
X317000Y58000D03*
X321500Y66500D03*
X332500Y63300D03*
X396216Y46875D03*
X412000Y175000D03*
X417300Y185200D03*
X418500Y229600D03*
X412000Y219300D03*
X441938Y132100D03*
Y309700D03*
X458946Y341216D03*
X455946Y357216D03*
X465946Y357016D03*
X471946Y341216D03*
X484446D03*
X517409Y322000D03*
X506309Y329000D03*
Y322000D03*
X517410Y329000D03*
X551430Y132400D03*
X580184Y117800D03*
X586184Y111800D03*
X580184Y105800D03*
X562830Y140300D03*
X574230Y132400D03*
X563007Y251677D03*
X581562Y272005D03*
X562830Y266500D03*
X571542Y289065D03*
X577808Y278085D03*
X594000Y257000D03*
X602200Y253200D03*
X622003Y297500D03*
X641500Y232000D03*
X626026Y266657D03*
X629684Y260000D03*
X630684Y269000D03*
X627184Y287500D03*
X629684Y300000D03*
X627684Y293425D03*
X635600Y309416D03*
X657784Y40500D03*
Y96000D03*
X676638Y230894D03*
X666000Y241000D03*
X681684Y230820D03*
X676756Y257572D03*
X677184Y267000D03*
X680100Y297600D03*
X672242Y294442D03*
X673800Y289400D03*
X672200Y283700D03*
X675100Y304500D03*
X702223Y197419D03*
X689684Y230762D03*
X698497Y257727D03*
X707980Y252376D03*
X713184Y298500D03*
X695734Y296950D03*
X687854Y299000D03*
X720100Y185000D03*
X725000Y292500D03*
X721214Y284666D03*
X758600Y185000D03*
X788100Y383000D03*
X882660Y350840D03*
X885100Y361500D03*
X974500Y185000D03*
X978600Y310955D03*
X1013000Y185000D03*
X1034360Y254000D03*
X1041840Y253760D03*
X1040539Y266826D03*
X1045337Y298773D03*
X1021414Y355979D03*
X1017300Y385600D03*
X1041400Y368600D03*
X1074500Y43500D03*
Y99000D03*
X1066550Y255050D03*
X1072286Y294922D03*
X1064032Y294958D03*
X1050500Y336500D03*
X1078100Y253500D03*
X1082850Y256750D03*
X1086850Y265750D03*
X1087100Y260500D03*
X1089937Y271255D03*
X1077300Y294000D03*
X1085100Y285000D03*
X1090500Y290500D03*
X1085528Y294428D03*
X1101200Y355600D03*
X1131700Y263000D03*
X1127100Y242500D03*
X1132600Y252000D03*
X1134600Y258575D03*
X1136258Y285343D03*
X1132600Y292000D03*
X1133459Y277272D03*
X1131600Y283000D03*
X1120000Y317500D03*
Y323000D03*
X1113000Y339000D03*
X1133000Y353240D03*
X1140100Y254500D03*
X1160200Y299800D03*
X1152647Y294655D03*
X1166000Y352500D03*
X1182100Y105800D03*
X1167371Y296240D03*
X1182409Y286245D03*
X1180808Y297945D03*
X1176000Y350000D03*
X1168500Y344425D03*
X1210500Y132400D03*
Y265600D03*
X1225930Y359148D03*
X1244874Y330000D03*
X1255975D03*
X1242930Y359148D03*
X1255975Y337000D03*
X1260340Y359284D03*
X1286113Y378312D03*
X1320346Y112300D03*
X1345500Y165500D03*
X1342900Y209600D03*
X1320346Y289900D03*
X1350000Y154800D03*
X1350100Y199250D03*
X1406230Y15076D03*
X1400230Y21076D03*
X1412230D03*
X1494000Y59500D03*
X1490000Y80500D03*
X1499228Y74500D03*
X1490228Y66500D03*
X1505100Y64500D03*
X1551000Y96500D03*
X1567500Y67000D03*
X1618800Y76700D03*
X1597100Y145000D03*
Y126000D03*
X1625370Y103940D03*
X1632336Y109117D03*
X1631323Y115140D03*
X1636400Y127429D03*
X1641932Y122969D03*
X1643217Y135054D03*
X1635000Y142500D03*
X1634500Y147500D03*
X1647500Y140000D03*
X1635000Y152925D03*
X1650117Y180000D03*
X1622100Y155931D03*
X1630075Y158000D03*
X1641500Y178000D03*
X1635000Y164500D03*
X1657050Y116760D03*
X1669800Y120400D03*
X1675800D03*
X1656657Y127365D03*
X1651325Y125076D03*
X1673000Y141000D03*
Y146500D03*
X1676350Y160251D03*
X1673250Y151750D03*
X1674500Y175000D03*
X1680000D03*
X1666500Y178500D03*
X1677000Y169500D03*
X1680500Y165000D03*
X1661000Y178500D03*
X1672050Y181550D03*
X1668075Y189500D03*
X1679176Y194760D03*
X1664000Y202500D03*
X1658500Y183000D03*
X1652500Y185000D03*
X1677500Y182000D03*
X1654000Y192500D03*
X1660000Y193500D03*
X1706100Y92000D03*
X1701350Y114250D03*
X1696600Y119000D03*
X1685100Y127500D03*
X1702525Y129500D03*
X1692600Y135975D03*
X1688100Y145560D03*
X1685000Y133000D03*
X1685976Y153500D03*
X1688100Y173060D03*
Y162060D03*
X1709600Y158000D03*
X1682000Y160000D03*
X1701100Y182000D03*
X1688100Y184220D03*
X1702075Y205500D03*
X1719075Y107016D03*
X1721685Y95940D03*
X1727200Y104500D03*
X1721000Y142525D03*
X1714100Y144925D03*
X1729411Y143661D03*
X1727100Y164280D03*
X1715525Y168500D03*
X1722063Y156962D03*
X1726099Y153000D03*
X1720100Y179500D03*
X1729411Y159161D03*
X1733500Y173760D03*
X1738740Y191500D03*
X1759600Y114500D03*
X1767425Y107000D03*
X1761600Y124524D03*
X1764000Y142525D03*
X1770575Y137000D03*
X1763075Y178900D03*
X1767075Y155484D03*
X1769476Y168500D03*
X1743500Y181000D03*
X1742500Y198000D03*
X1747925Y204000D03*
X1743500Y187500D03*
X1762454Y320347D03*
X1769300Y329400D03*
X1747235Y355989D03*
X1769300Y340600D03*
X1769692Y334649D03*
X1767700Y346200D03*
X1747235Y363689D03*
Y371389D03*
X1773000Y142525D03*
X1773500Y129500D03*
X1773000Y158000D03*
X1772600Y177300D03*
X1795600Y308000D03*
X1817500Y188000D03*
X1811500Y186000D03*
X1847164Y419238D03*
X1842164Y432338D03*
X1847164Y430568D03*
X1852164Y435538D03*
X1837164Y428238D03*
G54D72*
X1846142Y230433D03*
Y240433D03*
X1856772D03*
Y230433D03*
X1846142Y250433D03*
Y260433D03*
Y270433D03*
X1856772D03*
Y260433D03*
Y250433D03*
X1846142Y280433D03*
Y290433D03*
Y300433D03*
X1856772D03*
Y290433D03*
Y280433D03*
X1848957Y324213D03*
X1843957Y329213D03*
X1848957Y314213D03*
X1843957Y319213D03*
X1853957Y329213D03*
Y319213D03*
X1858957Y324213D03*
Y314213D03*
X1848957Y334213D03*
Y344213D03*
X1843957Y339213D03*
Y349213D03*
X1853957D03*
Y339213D03*
X1858957Y344213D03*
Y334213D03*
G54D28*
X438100Y176084D03*
X612684Y313984D03*
X616684D03*
X635184Y296484D03*
Y304484D03*
X622184Y305484D03*
X1062600Y302484D03*
X1082100D03*
X1074100D03*
X1086100D03*
X1078100D03*
X1090100D03*
X1127100Y274484D03*
X1112500Y361984D03*
X1149600Y249484D03*
X1145600D03*
X1154600Y302484D03*
X1135000Y363984D03*
X1139000D03*
X1176000Y356484D03*
X1170500D03*
X1324100Y156484D03*
X1641077Y130488D03*
G54D37*
X594600Y251240D03*
Y243760D03*
X665684Y224240D03*
Y216760D03*
X673684Y224240D03*
Y216760D03*
X681684Y224240D03*
Y216760D03*
X708600Y196740D03*
Y189260D03*
X689684Y224240D03*
Y216760D03*
X690184Y312760D03*
Y320240D03*
X699184Y312760D03*
Y320240D03*
X1024600Y197240D03*
Y189760D03*
X1063100Y239240D03*
Y231760D03*
X1072100Y239240D03*
Y231760D03*
X1072600Y327760D03*
X1064600D03*
X1072600Y335240D03*
X1064600D03*
X1088100Y327760D03*
X1080600D03*
X1088100Y335240D03*
X1080600D03*
X1113000Y353240D03*
Y345760D03*
G54D46*
X635200Y269000D03*
Y264500D03*
Y260000D03*
Y273500D03*
Y288500D03*
X663200Y262500D03*
Y254500D03*
X661200Y267000D03*
X663200Y258500D03*
X664616Y304500D03*
Y300500D03*
X707516Y208000D03*
X688700Y306500D03*
X1024616Y212500D03*
X1061616Y245500D03*
X1066116Y250000D03*
X1067116Y301000D03*
X1094616Y259500D03*
Y255500D03*
Y267500D03*
Y263500D03*
Y243500D03*
Y271500D03*
X1090616Y283000D03*
X1117616Y243500D03*
X1124116Y267500D03*
X1119616Y258500D03*
Y254000D03*
X1120116Y274500D03*
X1131116Y270000D03*
X1154116Y249500D03*
X1154616Y306500D03*
X1162516Y338000D03*
X1627016Y139000D03*
Y149500D03*
X1652516Y138000D03*
X1678016Y141500D03*
Y145500D03*
Y153500D03*
G54D19*
X137303Y601693D03*
Y609567D03*
Y617441D03*
Y625315D03*
Y633189D03*
Y641063D03*
Y648937D03*
Y656811D03*
X163878Y601693D03*
X156004D03*
X145177D03*
X163878Y609567D03*
Y617441D03*
Y625315D03*
Y633189D03*
X156004Y609567D03*
Y617441D03*
Y625315D03*
Y633189D03*
X145177Y609567D03*
Y617441D03*
Y625315D03*
Y633189D03*
X163878Y641063D03*
Y648937D03*
Y656811D03*
X156004Y641063D03*
Y648937D03*
Y656811D03*
X145177Y641063D03*
Y648937D03*
Y656811D03*
X163878Y664685D03*
X156004D03*
X145177D03*
X192126Y633189D03*
Y625315D03*
Y617441D03*
Y656811D03*
Y648937D03*
Y664685D03*
X200000Y633189D03*
Y625315D03*
Y617441D03*
X215748Y633189D03*
Y625315D03*
Y617441D03*
X223622Y633189D03*
Y625315D03*
X215748Y656811D03*
Y648937D03*
X223622Y656811D03*
Y648937D03*
X200000Y656811D03*
Y648937D03*
X215748Y664685D03*
X223622D03*
X200000D03*
X250866Y20827D03*
Y10197D03*
X255906Y617441D03*
X248032D03*
X255906Y625315D03*
Y633189D03*
X248032D03*
Y625315D03*
X255906Y648937D03*
X248032D03*
X255906Y656811D03*
X248032D03*
X255906Y664685D03*
X248032D03*
X279646Y23012D03*
Y13012D03*
X284646Y18012D03*
X274646D03*
X284646Y8012D03*
X260866Y20827D03*
Y10197D03*
X279528Y617441D03*
X271654D03*
X279528Y625315D03*
Y633189D03*
X271654D03*
Y625315D03*
X279528Y648937D03*
X271654D03*
X279528Y656811D03*
X271654D03*
X279528Y664685D03*
X271654D03*
X289646Y23012D03*
Y13012D03*
X295276Y617441D03*
Y625315D03*
Y633189D03*
X303150D03*
Y625315D03*
Y648937D03*
X295276D03*
X303150Y656811D03*
X295276D03*
X303150Y664685D03*
X295276D03*
X1437008Y617441D03*
X1429134D03*
X1437008Y625315D03*
Y633189D03*
X1429134D03*
Y625315D03*
X1437008Y648937D03*
X1429134D03*
X1437008Y656811D03*
X1429134D03*
X1437008Y664685D03*
X1429134D03*
X1465197Y18012D03*
X1451417Y20827D03*
X1441417D03*
X1451417Y10197D03*
X1441417D03*
X1460630Y617441D03*
X1452756D03*
X1460630Y625315D03*
Y633189D03*
X1452756D03*
Y625315D03*
X1460630Y648937D03*
X1452756D03*
X1460630Y656811D03*
X1452756D03*
X1460630Y664685D03*
X1452756D03*
X1480197Y23012D03*
X1470197D03*
X1480197Y13012D03*
X1470197D03*
X1475197Y18012D03*
Y8012D03*
X1476378Y617441D03*
Y625315D03*
Y633189D03*
X1484252D03*
Y625315D03*
Y648937D03*
X1476378D03*
X1484252Y656811D03*
X1476378D03*
X1484252Y664685D03*
X1476378D03*
X1508661Y633189D03*
Y625315D03*
Y617441D03*
X1516535Y633189D03*
Y625315D03*
Y617441D03*
X1508661Y656811D03*
Y648937D03*
X1516535Y656811D03*
Y648937D03*
X1508661Y664685D03*
X1516535D03*
X1532283Y633189D03*
Y625315D03*
Y617441D03*
X1540157Y633189D03*
Y625315D03*
X1532283Y656811D03*
Y648937D03*
X1540157Y656811D03*
Y648937D03*
X1532283Y664685D03*
X1540157D03*
X1587107Y601693D03*
X1576280D03*
X1568406D03*
X1587107Y609567D03*
Y617441D03*
Y625315D03*
Y633189D03*
X1576280Y609567D03*
Y617441D03*
Y625315D03*
Y633189D03*
X1568406Y609567D03*
Y617441D03*
Y625315D03*
Y633189D03*
X1587107Y641063D03*
Y648937D03*
Y656811D03*
X1576280Y641063D03*
Y648937D03*
Y656811D03*
X1568406Y641063D03*
Y648937D03*
Y656811D03*
X1587107Y664685D03*
X1576280D03*
X1594981Y601693D03*
Y609567D03*
Y617441D03*
Y625315D03*
Y633189D03*
Y641063D03*
Y648937D03*
Y656811D03*
Y664685D03*
G54D73*
X1851457Y220433D03*
X1856772Y360433D03*
G54D64*
X1152155Y276000D03*
G54D55*
X726100Y195008D03*
Y220992D03*
X752600Y195008D03*
Y220992D03*
X980500Y195008D03*
Y220992D03*
X1007000Y195008D03*
Y220992D03*
G54D74*
G01X586244Y288203D02*
X586750D01*
X589917Y285036D01*
X591464D01*
X591642Y284858D01*
X593298D01*
G01X587871Y289830D02*
Y289294D01*
X590538Y286627D01*
X591426D01*
X591626Y286827D01*
X593198D01*
G01X583449Y280532D02*
X583918D01*
X585350Y279100D01*
X591499D01*
X591646Y278953D01*
X593298D01*
G01X584885Y282351D02*
Y281787D01*
X586072Y280600D01*
X591301D01*
X591622Y280921D01*
X593298D01*
G01Y282890D02*
X590298D01*
G01X593298Y276984D02*
X590298D01*
G01X695259Y251000D02*
Y248020D01*
G01Y251000D02*
Y252500D01*
X694399Y253360D01*
Y255960D01*
X695502Y257063D01*
Y262488D01*
X695734Y262720D01*
Y264420D01*
G01X707544D02*
Y261660D01*
X706984Y261100D01*
G01X709514Y264420D02*
Y261670D01*
X710084Y261100D01*
G01X692109Y251000D02*
Y248020D01*
G01Y251000D02*
Y252500D01*
X692899Y253290D01*
Y256582D01*
X694002Y257685D01*
Y262474D01*
X693764Y262712D01*
Y264420D01*
G01X1070175Y301000D02*
Y299500D01*
X1069385Y298710D01*
Y295418D01*
X1068282Y294315D01*
Y289526D01*
X1068520Y289288D01*
Y287580D01*
G01X1067025Y301000D02*
Y299500D01*
X1067885Y298640D01*
Y296040D01*
X1066782Y294937D01*
Y289512D01*
X1066550Y289280D01*
Y287580D01*
G01X1052770D02*
Y290330D01*
X1052200Y290900D01*
G01X1054740Y287580D02*
Y290340D01*
X1055300Y290900D01*
G01X1070175Y301000D02*
Y303980D01*
G01X1067025Y301000D02*
Y303980D01*
G01X1157138Y303000D02*
Y300425D01*
X1156138Y299425D01*
X1154600D01*
G01X1174934Y267349D02*
X1174480Y266895D01*
X1170849D01*
X1170602Y267142D01*
X1168986D01*
G01X1174934Y265049D02*
X1174588Y265395D01*
X1170899D01*
X1170677Y265173D01*
X1169086D01*
G01X1180323Y274647D02*
X1179827D01*
X1176480Y271300D01*
X1170899D01*
X1170678Y271079D01*
X1168986D01*
G01X1178697Y276274D02*
Y275639D01*
X1175858Y272800D01*
X1170849D01*
X1170602Y273047D01*
X1168986D01*
G01Y275016D02*
X1171986D01*
G01X1168986Y269110D02*
X1171986D01*
G54D38*
X607668Y245500D03*
X608168Y302500D03*
X642168Y277500D03*
X631168Y282000D03*
X638168Y284500D03*
X642668Y298000D03*
Y293500D03*
X644584Y308500D03*
X671668Y269000D03*
X667668Y292500D03*
Y296500D03*
Y280500D03*
Y284500D03*
Y288500D03*
X667584Y308500D03*
X710484Y212000D03*
X695168Y251000D03*
X700668Y306500D03*
X696168Y302000D03*
X1027584Y208500D03*
X1073584Y245500D03*
X1097584Y247500D03*
Y251500D03*
X1099084Y297500D03*
Y289500D03*
X1101084Y285000D03*
X1099084Y293500D03*
X1127084Y263500D03*
Y278500D03*
Y283000D03*
Y287500D03*
Y292000D03*
X1629984Y146000D03*
Y142500D03*
Y153500D03*
X1664084Y138000D03*
X1680984Y149500D03*
X1738984Y181000D03*
Y186500D03*
X1769984Y184000D03*
G54D29*
X438100Y173117D03*
X612684Y311017D03*
X616684D03*
X635184Y293517D03*
Y301517D03*
X622184Y302517D03*
X1062600Y299517D03*
X1082100D03*
X1074100D03*
X1086100D03*
X1078100D03*
X1090100D03*
X1127100Y271517D03*
X1112500Y359017D03*
X1149600Y246517D03*
X1145600D03*
X1154600Y299517D03*
X1135000Y361017D03*
X1139000D03*
X1176000Y353517D03*
X1170500D03*
X1324100Y153517D03*
X1641077Y127521D03*
G54D56*
X729184Y285800D03*
Y274200D03*
X1033100Y266200D03*
Y277800D03*
X1055100Y301200D03*
Y312800D03*
G54D47*
X638167Y269000D03*
Y264500D03*
Y260000D03*
Y273500D03*
Y288500D03*
X666167Y262500D03*
Y254500D03*
X664167Y267000D03*
X666167Y258500D03*
X667583Y304500D03*
Y300500D03*
X710483Y208000D03*
X691667Y306500D03*
X1027583Y212500D03*
X1064583Y245500D03*
X1069083Y250000D03*
X1070083Y301000D03*
X1097583Y259500D03*
Y255500D03*
Y267500D03*
Y263500D03*
Y243500D03*
Y271500D03*
X1093583Y283000D03*
X1120583Y243500D03*
X1127083Y267500D03*
X1122583Y258500D03*
Y254000D03*
X1123083Y274500D03*
X1134083Y270000D03*
X1157083Y249500D03*
X1157583Y306500D03*
X1165483Y338000D03*
X1629983Y139000D03*
Y149500D03*
X1655483Y138000D03*
X1680983Y141500D03*
Y145500D03*
Y153500D03*
G54D65*
X1154600Y314150D03*
G54D75*
G01X593298Y267142D02*
X586425D01*
X581562Y272005D01*
G01X577808Y278085D02*
X581679D01*
X590654Y269110D01*
X593298D01*
G01X606084Y293100D02*
X607668Y291516D01*
Y289386D01*
G01X1156200Y258900D02*
X1154616Y260484D01*
Y262614D01*
G01X1154025Y249500D02*
Y247000D01*
G01X1150679Y262614D02*
Y257421D01*
X1154025Y254075D01*
Y249500D01*
G01X1179977Y283813D02*
X1179054Y282890D01*
X1168986D01*
G01X1176590Y286122D02*
X1175326Y284858D01*
X1168986D01*
G54D39*
X604701Y245500D03*
X605201Y302500D03*
X639201Y277500D03*
X628201Y282000D03*
X635201Y284500D03*
X639701Y298000D03*
Y293500D03*
X641617Y308500D03*
X668701Y269000D03*
X664701Y292500D03*
Y296500D03*
Y280500D03*
Y284500D03*
Y288500D03*
X664617Y308500D03*
X707517Y212000D03*
X692201Y251000D03*
X697701Y306500D03*
X693201Y302000D03*
X1024617Y208500D03*
X1070617Y245500D03*
X1094617Y247500D03*
Y251500D03*
X1096117Y297500D03*
Y289500D03*
X1098117Y285000D03*
X1096117Y293500D03*
X1124117Y263500D03*
Y278500D03*
Y283000D03*
Y287500D03*
Y292000D03*
X1627017Y146000D03*
Y142500D03*
Y153500D03*
X1661117Y138000D03*
X1678017Y149500D03*
X1736017Y181000D03*
Y186500D03*
X1767017Y184000D03*
G54D66*
X1157740Y337941D03*
Y343059D03*
X1150260D03*
Y340500D03*
Y337941D03*
G54D48*
X706600Y234799D03*
Y222201D03*
X1036600Y300701D03*
Y313299D03*
G54D57*
X802087Y145984D03*
X792087D03*
X802087Y135984D03*
X792087D03*
X802087Y180984D03*
X792087D03*
X802087Y170984D03*
X792087D03*
X802087Y200984D03*
X792087D03*
X802087Y230984D03*
X792087D03*
X802087Y220984D03*
X792087D03*
X802087Y265984D03*
X792087D03*
X802087Y255984D03*
X792087D03*
X822087Y145984D03*
X812087D03*
X822087Y135984D03*
X812087D03*
X822087Y180984D03*
X812087D03*
X822087Y170984D03*
X812087D03*
Y200984D03*
X822087Y230984D03*
X812087D03*
X822087Y220984D03*
X812087D03*
X822087Y265984D03*
X812087D03*
X822087Y255984D03*
X812087D03*
X920197Y145984D03*
X910197D03*
X920197Y135984D03*
X910197D03*
X920197Y180984D03*
X910197D03*
X920197Y170984D03*
X910197D03*
X920197Y200984D03*
X910197D03*
X920197Y230984D03*
X910197D03*
X920197Y220984D03*
X910197D03*
X920197Y265984D03*
X910197D03*
X920197Y255984D03*
X910197D03*
X940197Y145984D03*
X930197D03*
X940197Y135984D03*
X930197D03*
X940197Y180984D03*
X930197D03*
X940197Y170984D03*
X930197D03*
Y200984D03*
X940197Y230984D03*
X930197D03*
X940197Y220984D03*
X930197D03*
X940197Y265984D03*
X930197D03*
X940197Y255984D03*
X930197D03*
G54D76*
G01X1647837Y121812D02*
Y124963D01*
X1645401Y127399D01*
X1645277D01*
G01X1643500Y173398D02*
X1649500D01*
G01X1662350Y143850D02*
X1663748Y145248D01*
X1666500D01*
G36*
G01X834887Y88479D02*
G02X822087Y101284I-12800J5D01*
G02X834887Y88489I0J-12800D01*
G01X830387D01*
G03X822087Y80183I-8300J-5D01*
G03X830387Y88479I0J8301D01*
G01X834887D01*
G37*
G36*
G01Y313479D02*
G02X822087Y326284I-12800J5D01*
G02X834887Y313489I0J-12800D01*
G01X830387D01*
G03X822087Y305183I-8300J-5D01*
G03X830387Y313479I0J8301D01*
G01X834887D01*
G37*
G36*
G01X952997Y88479D02*
G02X940197Y101284I-12800J5D01*
G02X952997Y88489I0J-12800D01*
G01X948497D01*
G03X940197Y80183I-8300J-5D01*
G03X948497Y88479I0J8301D01*
G01X952997D01*
G37*
G36*
G01Y313479D02*
G02X940197Y326284I-12800J5D01*
G02X952997Y313489I0J-12800D01*
G01X948497D01*
G03X940197Y305183I-8300J-5D01*
G03X948497Y313479I0J8301D01*
G01X952997D01*
G37*
G54D67*
X1170941Y361260D03*
X1176059D03*
Y368740D03*
X1173500D03*
X1170941D03*
G54D49*
X691214Y278000D03*
X1071070Y274000D03*
G54D77*
G01X616666Y246839D02*
X620466D01*
G01X640702Y241720D02*
X629381D01*
X626821Y244280D01*
X616666D01*
G01X1121582Y310280D02*
X1132903D01*
X1135463Y307720D01*
X1145618D01*
G01Y305161D02*
X1141600D01*
G54D59*
X822087Y88484D03*
Y313484D03*
X940197Y88484D03*
Y313484D03*
G54D68*
G01X415200Y180100D02*
X408100D01*
G01X434100Y176175D02*
X438100D01*
G01D02*
X441613D01*
X441938Y176500D01*
G01X422000Y169925D02*
X427725D01*
X428100Y170300D01*
G01X417500Y169600D02*
X417825Y169925D01*
X422000D01*
G01Y173075D02*
Y174815D01*
G01Y217575D02*
Y219059D01*
G01X434100Y220575D02*
X438100D01*
G01D02*
X441613D01*
X441938Y220900D01*
G01X422000Y214425D02*
X420675Y213100D01*
G01X422000Y214425D02*
X427825D01*
G01X561155Y160784D02*
X561585Y160354D01*
Y155031D01*
X560280Y153726D01*
X558434D01*
X547828Y164332D01*
Y300049D01*
X556315Y308536D01*
X577229D01*
X581747Y304018D01*
Y292700D01*
X586244Y288203D01*
G01X564305Y160784D02*
X563885Y160364D01*
Y154077D01*
X561234Y151426D01*
X557480D01*
X545528Y163378D01*
Y301003D01*
X555361Y310836D01*
X578182D01*
X584047Y304971D01*
Y293654D01*
X587871Y289830D01*
G01X562830Y277000D02*
X563485Y276345D01*
X566688D01*
X573945Y269088D01*
Y262476D01*
X575479Y260942D01*
Y139322D01*
X570055Y133898D01*
X563428D01*
X562830Y133300D01*
G01Y273500D02*
X563336Y274006D01*
X565773D01*
X571645Y268134D01*
Y261522D01*
X573179Y259988D01*
Y140276D01*
X569101Y136198D01*
X563432D01*
X562830Y136800D01*
G01Y140300D02*
X563858Y141328D01*
X565859D01*
X569141Y144610D01*
Y257166D01*
X568808Y257499D01*
Y266840D01*
X566140Y269508D01*
X563322D01*
X562830Y270000D01*
G01Y266500D02*
X563526Y267196D01*
X565198D01*
X566508Y265886D01*
Y256639D01*
X566841Y256306D01*
Y145563D01*
X564906Y143628D01*
X563002D01*
X562830Y143800D01*
G01X571325Y292757D02*
X570611D01*
X568347Y290493D01*
Y287979D01*
X574117Y282209D01*
X581772D01*
X583449Y280532D01*
G01X571542Y289065D02*
X576098Y284509D01*
X582725D01*
X584885Y282351D01*
G01X607684Y234050D02*
X619054D01*
X620794Y235790D01*
G01X612684Y305575D02*
X616684D01*
G01D02*
Y307975D01*
G01X620794Y235790D02*
X622288D01*
G01X635184Y280575D02*
X637684D01*
G01X635184D02*
X632684D01*
X631259Y282000D01*
G01X622184Y305575D02*
Y308000D01*
G01X623500Y379000D02*
X636300Y391800D01*
X779300D01*
X788100Y383000D01*
G01X663109Y262500D02*
X660684D01*
G01X664609Y288500D02*
X662184D01*
G01X664609Y284500D02*
X662184D01*
G01X664525Y308500D02*
X662125D01*
G01X704200Y206569D02*
Y203000D01*
G01X707425Y208000D02*
X705631D01*
X704200Y206569D01*
G01X699684Y249425D02*
Y248060D01*
G01D02*
X698743Y247119D01*
X698433D01*
G01X822087Y200984D02*
X827083D01*
X847200Y221101D01*
Y323900D01*
X788100Y383000D01*
G01X940197Y200984D02*
X933254Y194041D01*
X900460D01*
X885773Y208728D01*
Y327016D01*
X953588Y394831D01*
X1031769D01*
X1036800Y389800D01*
Y373200D01*
X1041400Y368600D01*
G01X1027675Y208500D02*
X1029100D01*
X1030100Y207500D01*
G01D02*
Y204600D01*
X1029000Y203500D01*
G01X1041400Y368600D02*
X1049500Y360500D01*
X1074260D01*
G01X1062600Y302575D02*
Y305000D01*
G01X1097675Y243500D02*
X1100100D01*
G01X1097675Y267500D02*
Y263500D01*
G01D02*
X1100500D01*
G01X1099175Y289500D02*
X1101600D01*
G01X1088100Y335240D02*
X1109240D01*
X1113000Y339000D01*
G01X1127100Y271425D02*
X1124600D01*
G01X1127100D02*
X1129600D01*
X1131025Y270000D01*
G01X1113000Y339000D02*
Y345760D01*
G01X1135000Y360925D02*
X1132924D01*
X1130759Y358760D01*
X1128224D01*
G01X1113000Y353240D02*
X1133000D01*
G01D02*
X1139000Y359240D01*
Y360925D01*
G01X1118776Y366240D02*
X1122000D01*
G01X1112500Y362075D02*
Y364700D01*
G01X1107000Y361400D02*
Y363500D01*
X1106000Y364500D01*
G01X1149600Y246425D02*
X1145600D01*
G01D02*
Y244025D01*
G01X1140100Y246425D02*
Y244000D01*
G01X1154600Y317950D02*
Y321050D01*
G01Y312050D02*
X1157800D01*
G01X1163000Y347575D02*
X1166075D01*
X1168200Y349700D01*
G01X1157740Y337941D02*
X1162366D01*
X1162425Y338000D01*
G01D02*
Y340500D01*
G01X1150260Y343059D02*
X1147559D01*
X1147000Y342500D01*
G01X1135000Y364075D02*
Y366500D01*
G01X1139000Y364075D02*
Y366500D01*
G01Y360925D02*
X1135000D01*
G01X1200575Y160284D02*
Y162106D01*
X1205154Y166685D01*
Y255634D01*
X1189301Y271487D01*
X1182447D01*
X1178309Y267349D01*
X1174934D01*
G01X1197425Y160284D02*
Y162209D01*
X1202854Y167638D01*
Y254681D01*
X1188348Y269187D01*
X1183400D01*
X1179262Y265049D01*
X1174934D01*
G01X1196500Y293284D02*
X1197500Y294284D01*
Y295048D01*
X1195900Y296648D01*
X1193606D01*
X1190906Y293948D01*
Y285230D01*
X1180323Y274647D01*
G01X1201500Y293284D02*
X1200143Y294641D01*
Y295701D01*
X1196896Y298948D01*
X1192653D01*
X1188606Y294901D01*
Y286183D01*
X1178697Y276274D01*
G01X1170500Y356575D02*
X1169375D01*
X1167800Y355000D01*
G01X1176000Y353425D02*
Y350000D01*
G01X1170941Y361260D02*
Y357016D01*
X1170500Y356575D01*
G01X1165575Y338000D02*
Y340500D01*
G01X1170500Y353425D02*
Y351100D01*
X1171700Y349900D01*
G01X1176059Y368740D02*
X1178500D01*
G01X1199100Y270000D02*
X1199852Y269248D01*
X1202748D01*
X1211387Y260609D01*
Y147890D01*
X1204427Y140930D01*
X1199730D01*
X1199100Y140300D01*
G01Y133300D02*
X1199690Y133890D01*
X1206733D01*
X1217658Y144815D01*
Y268607D01*
X1209875Y276390D01*
X1199710D01*
X1199100Y277000D01*
G01Y143800D02*
X1199670Y143230D01*
X1203474D01*
X1209087Y148843D01*
Y259656D01*
X1201945Y266798D01*
X1199398D01*
X1199100Y266500D01*
G01Y273500D02*
X1199690Y274090D01*
X1208922D01*
X1215358Y267654D01*
Y145768D01*
X1205780Y136190D01*
X1199710D01*
X1199100Y136800D01*
G01X1340100Y153275D02*
Y155015D01*
G01X1328100Y156575D02*
X1324100D01*
G01D02*
X1320471D01*
X1320346Y156700D01*
G01X1334100Y150200D02*
X1334175Y150125D01*
X1340100D01*
G01X1344800Y149800D02*
X1344475Y150125D01*
X1340100D01*
G01X1340600Y197475D02*
Y199401D01*
G01X1344800Y193700D02*
Y193825D01*
X1344300Y194325D01*
X1340600D01*
G01X1334100Y194600D02*
X1334375Y194325D01*
X1340600D01*
G01X1320346Y201100D02*
X1320471Y200975D01*
X1324100D01*
G01D02*
X1328100D01*
G01X1347000Y160300D02*
X1354800D01*
X1355100Y160000D01*
G01X1347000Y204400D02*
X1355000D01*
G01X1475197Y8012D02*
X1476185Y9000D01*
X1481384D01*
X1483537Y11153D01*
X1484100Y12524D01*
Y15500D01*
X1486100Y17500D01*
G01X1626925Y142500D02*
X1624500D01*
G01X1626925Y146000D02*
X1624500D01*
G01X1655575Y138000D02*
X1658500D01*
G01X1661025D02*
X1658500D01*
G01X1661025D02*
Y142525D01*
X1662350Y143850D01*
G01X1664175Y138000D02*
X1667000D01*
G01X1681075Y149500D02*
X1684476D01*
X1685976Y148000D01*
G01X1681075Y153500D02*
Y155425D01*
X1680000Y156500D01*
G01X1758824Y183760D02*
X1763685D01*
X1763925Y184000D01*
X1766925D01*
G01D02*
Y181500D01*
G01X1749376Y191240D02*
X1746000D01*
G01X1770075Y184000D02*
Y181500D01*
G01X1786600Y254500D02*
Y352500D01*
X1782800Y356300D01*
X1777375D01*
X1642915Y111950D03*
X1639372Y114450D03*
X1646458Y111950D03*
X1642915Y114450D03*
X1639372Y111950D03*
X1646458Y114450D03*
X1650002Y111950D03*
Y114450D03*
G54D78*
G01X162583Y225798D02*
X166785Y230000D01*
G01D02*
X170987Y234202D01*
G01X162583D02*
X166785Y230000D01*
G01D02*
X170987Y225798D01*
G01X162583Y305798D02*
X166785Y310000D01*
G01D02*
X170987Y314202D01*
G01X162583D02*
X166785Y310000D01*
G01D02*
X170987Y305798D01*
G01X162583Y385798D02*
X166785Y390000D01*
G01D02*
X170987Y394202D01*
G01X162583D02*
X166785Y390000D01*
G01D02*
X170987Y385798D01*
G01X162583Y465798D02*
X166785Y470000D01*
G01D02*
X170987Y474202D01*
G01X162583D02*
X166785Y470000D01*
G01D02*
X170987Y465798D01*
G01X162583Y545798D02*
X166785Y550000D01*
G01D02*
X170987Y554202D01*
G01X162583D02*
X166785Y550000D01*
G01D02*
X170987Y545798D01*
G01X239583Y225798D02*
X243785Y230000D01*
G01D02*
X247987Y234202D01*
G01X239583D02*
X243785Y230000D01*
G01D02*
X247987Y225798D01*
G01X239583Y305798D02*
X243785Y310000D01*
G01D02*
X247987Y314202D01*
G01X239583D02*
X243785Y310000D01*
G01D02*
X247987Y305798D01*
G01X239583Y385798D02*
X243785Y390000D01*
G01D02*
X247987Y394202D01*
G01X239583D02*
X243785Y390000D01*
G01D02*
X247987Y385798D01*
G01X239583Y465798D02*
X243785Y470000D01*
G01D02*
X247987Y474202D01*
G01X239583D02*
X243785Y470000D01*
G01D02*
X247987Y465798D01*
G01X239583Y545798D02*
X243785Y550000D01*
G01D02*
X247987Y554202D01*
G01X239583D02*
X243785Y550000D01*
G01D02*
X247987Y545798D01*
G01X1484298Y225798D02*
X1488500Y230000D01*
G01D02*
X1492702Y234202D01*
G01X1484298D02*
X1488500Y230000D01*
G01D02*
X1492702Y225798D01*
G01X1484298Y305798D02*
X1488500Y310000D01*
G01D02*
X1492702Y314202D01*
G01X1484298D02*
X1488500Y310000D01*
G01D02*
X1492702Y305798D01*
G01X1484298Y385798D02*
X1488500Y390000D01*
G01D02*
X1492702Y394202D01*
G01X1484298D02*
X1488500Y390000D01*
G01D02*
X1492702Y385798D01*
G01X1484298Y465798D02*
X1488500Y470000D01*
G01D02*
X1492702Y474202D01*
G01X1484298D02*
X1488500Y470000D01*
G01D02*
X1492702Y465798D01*
G01X1484298Y545798D02*
X1488500Y550000D01*
G01D02*
X1492702Y554202D01*
G01X1484298D02*
X1488500Y550000D01*
G01D02*
X1492702Y545798D01*
G01X1561298Y225798D02*
X1565500Y230000D01*
G01D02*
X1569702Y234202D01*
G01X1561298D02*
X1565500Y230000D01*
G01D02*
X1569702Y225798D01*
G01X1561298Y305798D02*
X1565500Y310000D01*
G01D02*
X1569702Y314202D01*
G01X1561298D02*
X1565500Y310000D01*
G01D02*
X1569702Y305798D01*
G01X1561298Y385798D02*
X1565500Y390000D01*
G01D02*
X1569702Y394202D01*
G01X1561298D02*
X1565500Y390000D01*
G01D02*
X1569702Y385798D01*
G01X1561298Y465798D02*
X1565500Y470000D01*
G01D02*
X1569702Y474202D01*
G01X1561298D02*
X1565500Y470000D01*
G01D02*
X1569702Y465798D01*
G01X1561298Y545798D02*
X1565500Y550000D01*
G01D02*
X1569702Y554202D01*
G01X1561298D02*
X1565500Y550000D01*
G01D02*
X1569702Y545798D01*
G54D69*
X1643500Y147807D03*
Y145248D03*
Y173398D03*
Y170839D03*
Y168280D03*
Y165721D03*
Y163162D03*
Y160603D03*
Y158043D03*
Y155484D03*
Y152925D03*
Y150366D03*
X1666500Y145248D03*
Y147807D03*
Y150366D03*
Y152925D03*
Y155484D03*
Y158043D03*
Y160603D03*
Y163162D03*
Y165721D03*
Y168280D03*
Y170839D03*
Y173398D03*
G54D79*
G01X-457143Y-1211429D02*
Y2242857D01*
X4308572D01*
Y-1211429D01*
X-457143D01*
G01X37000Y-995000D02*
Y-1070000D01*
X537000D01*
Y-995000D01*
X37000D01*
G01X49000Y-1060000D02*
Y-1065000D01*
G01X47543Y-1060000D02*
X50457D01*
G01X55367Y-1065000D02*
X52833D01*
Y-1060000D01*
X55367D01*
G01X54353Y-1062417D02*
X52833D01*
G01X57933Y-1060000D02*
Y-1065000D01*
X60467D01*
G01X64300Y-1065167D02*
X64173Y-1065083D01*
Y-1064917D01*
X64300Y-1064833D01*
X64427Y-1064917D01*
Y-1065083D01*
X64300Y-1065167D01*
G01Y-1062917D02*
X64173Y-1062833D01*
Y-1062667D01*
X64300Y-1062583D01*
X64427Y-1062667D01*
Y-1062833D01*
X64300Y-1062917D01*
G01X69083Y-1066667D02*
X68450Y-1065833D01*
X68133Y-1065000D01*
Y-1061667D01*
X68450Y-1060833D01*
X69083Y-1060000D01*
G01X74500D02*
X73993Y-1060167D01*
X73613Y-1060583D01*
X73360Y-1061083D01*
X73170Y-1061750D01*
X73107Y-1062500D01*
X73170Y-1063250D01*
X73360Y-1063917D01*
X73613Y-1064417D01*
X73993Y-1064833D01*
X74500Y-1065000D01*
X75007Y-1064833D01*
X75387Y-1064417D01*
X75640Y-1063917D01*
X75830Y-1063250D01*
X75893Y-1062500D01*
X75830Y-1061750D01*
X75640Y-1061083D01*
X75387Y-1060583D01*
X75007Y-1060167D01*
X74500Y-1060000D01*
G01X78207Y-1064000D02*
X78587Y-1064583D01*
X79093Y-1064917D01*
X79663Y-1065000D01*
X80170Y-1064917D01*
X80677Y-1064500D01*
X80993Y-1064000D01*
X81057Y-1063500D01*
X80930Y-1062917D01*
X80487Y-1062500D01*
X80043Y-1062333D01*
X79473D01*
G01X80043D02*
X80423Y-1062083D01*
X80740Y-1061667D01*
X80867Y-1061167D01*
X80740Y-1060667D01*
X80423Y-1060250D01*
X79853Y-1060000D01*
X79283Y-1060083D01*
X78713Y-1060417D01*
G01X85017Y-1066667D02*
X85650Y-1065833D01*
X85967Y-1065000D01*
Y-1061667D01*
X85650Y-1060833D01*
X85017Y-1060000D01*
G01X88407Y-1064000D02*
X88787Y-1064583D01*
X89293Y-1064917D01*
X89863Y-1065000D01*
X90370Y-1064917D01*
X90877Y-1064500D01*
X91193Y-1064000D01*
X91257Y-1063500D01*
X91130Y-1062917D01*
X90687Y-1062500D01*
X90243Y-1062333D01*
X89673D01*
G01X90243D02*
X90623Y-1062083D01*
X90940Y-1061667D01*
X91067Y-1061167D01*
X90940Y-1060667D01*
X90623Y-1060250D01*
X90053Y-1060000D01*
X89483Y-1060083D01*
X88913Y-1060417D01*
G01X93697Y-1060833D02*
X94077Y-1060333D01*
X94520Y-1060083D01*
X95027Y-1060000D01*
X95660Y-1060167D01*
X96103Y-1060583D01*
X96230Y-1061083D01*
X96167Y-1061583D01*
X95913Y-1062000D01*
X94647Y-1062833D01*
X94077Y-1063417D01*
X93697Y-1064250D01*
X93570Y-1065000D01*
X96230D01*
G01X99873D02*
X100000Y-1063917D01*
X100190Y-1063000D01*
X100443Y-1062167D01*
X100760Y-1061250D01*
X101267Y-1060000D01*
X98733D01*
G01X104277Y-1063333D02*
X105923D01*
G01X108997Y-1060833D02*
X109377Y-1060333D01*
X109820Y-1060083D01*
X110327Y-1060000D01*
X110960Y-1060167D01*
X111403Y-1060583D01*
X111530Y-1061083D01*
X111467Y-1061583D01*
X111213Y-1062000D01*
X109947Y-1062833D01*
X109377Y-1063417D01*
X108997Y-1064250D01*
X108870Y-1065000D01*
X111530D01*
G01X113907Y-1064000D02*
X114287Y-1064583D01*
X114793Y-1064917D01*
X115363Y-1065000D01*
X115870Y-1064917D01*
X116377Y-1064500D01*
X116693Y-1064000D01*
X116757Y-1063500D01*
X116630Y-1062917D01*
X116187Y-1062500D01*
X115743Y-1062333D01*
X115173D01*
G01X115743D02*
X116123Y-1062083D01*
X116440Y-1061667D01*
X116567Y-1061167D01*
X116440Y-1060667D01*
X116123Y-1060250D01*
X115553Y-1060000D01*
X114983Y-1060083D01*
X114413Y-1060417D01*
G01X121160Y-1065000D02*
Y-1060000D01*
X118817Y-1063583D01*
X121983D01*
G01X124107Y-1064250D02*
X124487Y-1064667D01*
X124930Y-1064917D01*
X125500Y-1065000D01*
X126070Y-1064833D01*
X126513Y-1064500D01*
X126830Y-1063917D01*
X126893Y-1063250D01*
X126767Y-1062583D01*
X126450Y-1062167D01*
X126007Y-1061833D01*
X125563Y-1061750D01*
X125120Y-1061833D01*
X124550Y-1062167D01*
X124740Y-1060000D01*
X126450D01*
G01X134497Y-1065000D02*
Y-1060000D01*
X136903D01*
G01X136017Y-1062417D02*
X134497D01*
G01X139217Y-1065000D02*
X140800Y-1060000D01*
X142383Y-1065000D01*
G01X141813Y-1063250D02*
X139787D01*
G01X144570Y-1065000D02*
X147230Y-1060000D01*
G01X144570D02*
X147230Y-1065000D01*
G01X151000Y-1065167D02*
X150873Y-1065083D01*
Y-1064917D01*
X151000Y-1064833D01*
X151127Y-1064917D01*
Y-1065083D01*
X151000Y-1065167D01*
G01Y-1062917D02*
X150873Y-1062833D01*
Y-1062667D01*
X151000Y-1062583D01*
X151127Y-1062667D01*
Y-1062833D01*
X151000Y-1062917D01*
G01X155783Y-1066667D02*
X155150Y-1065833D01*
X154833Y-1065000D01*
Y-1061667D01*
X155150Y-1060833D01*
X155783Y-1060000D01*
G01X161200D02*
X160693Y-1060167D01*
X160313Y-1060583D01*
X160060Y-1061083D01*
X159870Y-1061750D01*
X159807Y-1062500D01*
X159870Y-1063250D01*
X160060Y-1063917D01*
X160313Y-1064417D01*
X160693Y-1064833D01*
X161200Y-1065000D01*
X161707Y-1064833D01*
X162087Y-1064417D01*
X162340Y-1063917D01*
X162530Y-1063250D01*
X162593Y-1062500D01*
X162530Y-1061750D01*
X162340Y-1061083D01*
X162087Y-1060583D01*
X161707Y-1060167D01*
X161200Y-1060000D01*
G01X164907Y-1064000D02*
X165287Y-1064583D01*
X165793Y-1064917D01*
X166363Y-1065000D01*
X166870Y-1064917D01*
X167377Y-1064500D01*
X167693Y-1064000D01*
X167757Y-1063500D01*
X167630Y-1062917D01*
X167187Y-1062500D01*
X166743Y-1062333D01*
X166173D01*
G01X166743D02*
X167123Y-1062083D01*
X167440Y-1061667D01*
X167567Y-1061167D01*
X167440Y-1060667D01*
X167123Y-1060250D01*
X166553Y-1060000D01*
X165983Y-1060083D01*
X165413Y-1060417D01*
G01X171717Y-1066667D02*
X172350Y-1065833D01*
X172667Y-1065000D01*
Y-1061667D01*
X172350Y-1060833D01*
X171717Y-1060000D01*
G01X175107Y-1064000D02*
X175487Y-1064583D01*
X175993Y-1064917D01*
X176563Y-1065000D01*
X177070Y-1064917D01*
X177577Y-1064500D01*
X177893Y-1064000D01*
X177957Y-1063500D01*
X177830Y-1062917D01*
X177387Y-1062500D01*
X176943Y-1062333D01*
X176373D01*
G01X176943D02*
X177323Y-1062083D01*
X177640Y-1061667D01*
X177767Y-1061167D01*
X177640Y-1060667D01*
X177323Y-1060250D01*
X176753Y-1060000D01*
X176183Y-1060083D01*
X175613Y-1060417D01*
G01X180523Y-1064417D02*
X180967Y-1064833D01*
X181473Y-1065000D01*
X181980Y-1064833D01*
X182423Y-1064333D01*
X182740Y-1063583D01*
X182867Y-1062833D01*
Y-1061917D01*
X182740Y-1061167D01*
X182423Y-1060500D01*
X182043Y-1060167D01*
X181600Y-1060000D01*
X181093Y-1060167D01*
X180713Y-1060500D01*
X180460Y-1061000D01*
X180333Y-1061667D01*
X180460Y-1062250D01*
X180777Y-1062833D01*
X181157Y-1063167D01*
X181600Y-1063250D01*
X182107Y-1063083D01*
X182487Y-1062667D01*
X182867Y-1061917D01*
G01X186573Y-1065000D02*
X186700Y-1063917D01*
X186890Y-1063000D01*
X187143Y-1062167D01*
X187460Y-1061250D01*
X187967Y-1060000D01*
X185433D01*
G01X190977Y-1063333D02*
X192623D01*
G01X195507Y-1064000D02*
X195887Y-1064583D01*
X196393Y-1064917D01*
X196963Y-1065000D01*
X197470Y-1064917D01*
X197977Y-1064500D01*
X198293Y-1064000D01*
X198357Y-1063500D01*
X198230Y-1062917D01*
X197787Y-1062500D01*
X197343Y-1062333D01*
X196773D01*
G01X197343D02*
X197723Y-1062083D01*
X198040Y-1061667D01*
X198167Y-1061167D01*
X198040Y-1060667D01*
X197723Y-1060250D01*
X197153Y-1060000D01*
X196583Y-1060083D01*
X196013Y-1060417D01*
G01X200797Y-1062917D02*
X201240Y-1062333D01*
X201620Y-1062000D01*
X202127Y-1061833D01*
X202570Y-1062000D01*
X202887Y-1062333D01*
X203140Y-1062833D01*
X203203Y-1063417D01*
X203140Y-1063917D01*
X202887Y-1064417D01*
X202507Y-1064833D01*
X202063Y-1065000D01*
X201557Y-1064833D01*
X201113Y-1064333D01*
X200860Y-1063583D01*
X200797Y-1062750D01*
X200923Y-1061667D01*
X201113Y-1061083D01*
X201430Y-1060500D01*
X201873Y-1060083D01*
X202317Y-1060000D01*
X202760Y-1060167D01*
X203077Y-1060583D01*
G01X207100Y-1065000D02*
Y-1060000D01*
X206340Y-1061000D01*
G01Y-1065000D02*
X207860D01*
G01X212960D02*
Y-1060000D01*
X210617Y-1063583D01*
X213783D01*
G01X232000Y-995000D02*
Y-1070000D01*
G01Y-1045000D02*
X335000D01*
Y-1020000D01*
G01X232000D02*
X335000D01*
G01X337000Y-995000D02*
Y-1070000D01*
G01X335000Y-995000D02*
Y-1070000D01*
G01X342507Y-1055000D02*
Y-1050000D01*
X343773D01*
X344280Y-1050250D01*
X344660Y-1050583D01*
X344977Y-1051083D01*
X345230Y-1051667D01*
X345293Y-1052500D01*
X345230Y-1053333D01*
X344977Y-1053917D01*
X344660Y-1054417D01*
X344280Y-1054750D01*
X343773Y-1055000D01*
X342507D01*
G01X347417D02*
X349000Y-1050000D01*
X350583Y-1055000D01*
G01X350013Y-1053250D02*
X347987D01*
G01X354100Y-1050000D02*
Y-1055000D01*
G01X352643Y-1050000D02*
X355557D01*
G01X360467Y-1055000D02*
X357933D01*
Y-1050000D01*
X360467D01*
G01X359453Y-1052417D02*
X357933D01*
G01X364300Y-1055167D02*
X364173Y-1055083D01*
Y-1054917D01*
X364300Y-1054833D01*
X364427Y-1054917D01*
Y-1055083D01*
X364300Y-1055167D01*
G01Y-1052917D02*
X364173Y-1052833D01*
Y-1052667D01*
X364300Y-1052583D01*
X364427Y-1052667D01*
Y-1052833D01*
X364300Y-1052917D01*
G01X337000Y-1045000D02*
X537000D01*
G01X342633Y-1030000D02*
Y-1025000D01*
X344153D01*
X344660Y-1025250D01*
X345040Y-1025833D01*
X345167Y-1026500D01*
X345040Y-1027167D01*
X344723Y-1027667D01*
X344153Y-1027917D01*
X342633D01*
G01X347860Y-1030167D02*
X350140Y-1025000D01*
G01X352643Y-1030000D02*
Y-1025000D01*
X355557Y-1030000D01*
Y-1025000D01*
G01X359200Y-1030167D02*
X359073Y-1030083D01*
Y-1029917D01*
X359200Y-1029833D01*
X359327Y-1029917D01*
Y-1030083D01*
X359200Y-1030167D01*
G01Y-1027917D02*
X359073Y-1027833D01*
Y-1027667D01*
X359200Y-1027583D01*
X359327Y-1027667D01*
Y-1027833D01*
X359200Y-1027917D01*
G01X342633Y-1005000D02*
Y-1000000D01*
X344153D01*
X344660Y-1000250D01*
X345040Y-1000833D01*
X345167Y-1001500D01*
X345040Y-1002167D01*
X344723Y-1002667D01*
X344153Y-1002917D01*
X342633D01*
G01X347733Y-1005000D02*
Y-1000000D01*
X349317D01*
X349823Y-1000250D01*
X350140Y-1000583D01*
X350267Y-1001250D01*
X350140Y-1001917D01*
X349760Y-1002333D01*
X349317Y-1002583D01*
X347733D01*
G01X349317D02*
X350267Y-1005000D01*
G01X354100D02*
X353593Y-1004917D01*
X353150Y-1004583D01*
X352770Y-1004083D01*
X352517Y-1003500D01*
X352390Y-1002833D01*
Y-1002167D01*
X352517Y-1001500D01*
X352770Y-1000917D01*
X353150Y-1000417D01*
X353593Y-1000083D01*
X354100Y-1000000D01*
X354607Y-1000083D01*
X355050Y-1000417D01*
X355430Y-1000917D01*
X355683Y-1001500D01*
X355810Y-1002167D01*
Y-1002833D01*
X355683Y-1003500D01*
X355430Y-1004083D01*
X355050Y-1004583D01*
X354607Y-1004917D01*
X354100Y-1005000D01*
G01X357933Y-1004000D02*
X358250Y-1004500D01*
X358630Y-1004833D01*
X359073Y-1005000D01*
X359580Y-1004833D01*
X359960Y-1004500D01*
X360340Y-1004000D01*
X360467Y-1003333D01*
Y-1000000D01*
G01X365567Y-1005000D02*
X363033D01*
Y-1000000D01*
X365567D01*
G01X364553Y-1002417D02*
X363033D01*
G01X370793Y-1000417D02*
X370413Y-1000167D01*
X369970Y-1000000D01*
X369463D01*
X368893Y-1000250D01*
X368450Y-1000667D01*
X368133Y-1001167D01*
X367880Y-1002000D01*
X367817Y-1002750D01*
X367943Y-1003500D01*
X368133Y-1004000D01*
X368513Y-1004500D01*
X368957Y-1004833D01*
X369400Y-1005000D01*
X369843D01*
X370287Y-1004833D01*
X370667Y-1004583D01*
X370983Y-1004250D01*
G01X374500Y-1000000D02*
Y-1005000D01*
G01X373043Y-1000000D02*
X375957D01*
G01X379600Y-1005167D02*
X379473Y-1005083D01*
Y-1004917D01*
X379600Y-1004833D01*
X379727Y-1004917D01*
Y-1005083D01*
X379600Y-1005167D01*
G01Y-1002917D02*
X379473Y-1002833D01*
Y-1002667D01*
X379600Y-1002583D01*
X379727Y-1002667D01*
Y-1002833D01*
X379600Y-1002917D01*
G01X337000Y-1020000D02*
X537000D01*
G01X452000Y-1045000D02*
Y-1070000D01*
G01X454633Y-1047500D02*
Y-1052500D01*
X457167D01*
G01X460240Y-1047500D02*
X461760D01*
G01X461000D02*
Y-1052500D01*
G01X460240D02*
X461760D01*
G01X466607Y-1049833D02*
X466860Y-1049583D01*
X467050Y-1049167D01*
X467177Y-1048583D01*
X467050Y-1048083D01*
X466797Y-1047750D01*
X466353Y-1047500D01*
X464643D01*
Y-1052500D01*
X466733D01*
X467177Y-1052167D01*
X467430Y-1051667D01*
X467557Y-1051083D01*
X467430Y-1050500D01*
X467050Y-1050000D01*
X466607Y-1049833D01*
X464643D01*
G01X471200Y-1052667D02*
X471073Y-1052583D01*
Y-1052417D01*
X471200Y-1052333D01*
X471327Y-1052417D01*
Y-1052583D01*
X471200Y-1052667D01*
G01Y-1050417D02*
X471073Y-1050333D01*
Y-1050167D01*
X471200Y-1050083D01*
X471327Y-1050167D01*
Y-1050333D01*
X471200Y-1050417D01*
G01X495000Y-1045000D02*
Y-1070000D01*
G01X498900Y-1047500D02*
Y-1052500D01*
G01X497443Y-1047500D02*
X500357D01*
G01X504000Y-1052500D02*
X503620Y-1052417D01*
X503240Y-1052083D01*
X502987Y-1051500D01*
X502860Y-1050833D01*
X502987Y-1050167D01*
X503240Y-1049583D01*
X503620Y-1049250D01*
X504000Y-1049167D01*
X504380Y-1049250D01*
X504760Y-1049583D01*
X505013Y-1050167D01*
X505077Y-1050833D01*
X505013Y-1051500D01*
X504760Y-1052083D01*
X504380Y-1052417D01*
X504000Y-1052500D01*
G01X509100D02*
X508720Y-1052417D01*
X508340Y-1052083D01*
X508087Y-1051500D01*
X507960Y-1050833D01*
X508087Y-1050167D01*
X508340Y-1049583D01*
X508720Y-1049250D01*
X509100Y-1049167D01*
X509480Y-1049250D01*
X509860Y-1049583D01*
X510113Y-1050167D01*
X510177Y-1050833D01*
X510113Y-1051500D01*
X509860Y-1052083D01*
X509480Y-1052417D01*
X509100Y-1052500D01*
G01X514200D02*
Y-1047500D01*
G01X519300Y-1052667D02*
X519173Y-1052583D01*
Y-1052417D01*
X519300Y-1052333D01*
X519427Y-1052417D01*
Y-1052583D01*
X519300Y-1052667D01*
G01Y-1050417D02*
X519173Y-1050333D01*
Y-1050167D01*
X519300Y-1050083D01*
X519427Y-1050167D01*
Y-1050333D01*
X519300Y-1050417D01*
G01X495000Y-1020000D02*
Y-1045000D01*
G01X497633Y-1027500D02*
Y-1022500D01*
X499217D01*
X499723Y-1022750D01*
X500040Y-1023083D01*
X500167Y-1023750D01*
X500040Y-1024417D01*
X499660Y-1024833D01*
X499217Y-1025083D01*
X497633D01*
G01X499217D02*
X500167Y-1027500D01*
G01X505267D02*
X502733D01*
Y-1022500D01*
X505267D01*
G01X504253Y-1024917D02*
X502733D01*
G01X507517Y-1022500D02*
X509100Y-1027500D01*
X510683Y-1022500D01*
G01X514200Y-1027667D02*
X514073Y-1027583D01*
Y-1027417D01*
X514200Y-1027333D01*
X514327Y-1027417D01*
Y-1027583D01*
X514200Y-1027667D01*
G01Y-1025417D02*
X514073Y-1025333D01*
Y-1025167D01*
X514200Y-1025083D01*
X514327Y-1025167D01*
Y-1025333D01*
X514200Y-1025417D01*
G01X503013Y-1073167D02*
X503120Y-1073042D01*
X503200Y-1072833D01*
X503253Y-1072542D01*
X503200Y-1072292D01*
X503093Y-1072125D01*
X502907Y-1072000D01*
X502187D01*
Y-1074500D01*
X503067D01*
X503253Y-1074333D01*
X503360Y-1074083D01*
X503413Y-1073792D01*
X503360Y-1073500D01*
X503200Y-1073250D01*
X503013Y-1073167D01*
X502187D01*
G01X505480Y-1074500D02*
Y-1072833D01*
G01Y-1073125D02*
X505373Y-1072958D01*
X505213Y-1072875D01*
X505027Y-1072833D01*
X504840Y-1072917D01*
X504680Y-1073083D01*
X504573Y-1073333D01*
X504520Y-1073667D01*
X504573Y-1074000D01*
X504680Y-1074250D01*
X504840Y-1074417D01*
X505027Y-1074500D01*
X505213Y-1074458D01*
X505373Y-1074333D01*
X505480Y-1074167D01*
G01X506800Y-1074208D02*
X506933Y-1074375D01*
X507120Y-1074500D01*
X507280D01*
X507440Y-1074417D01*
X507547Y-1074292D01*
X507600Y-1074125D01*
X507573Y-1073875D01*
X507467Y-1073750D01*
X506987Y-1073500D01*
X506880Y-1073208D01*
X506933Y-1073000D01*
X507040Y-1072875D01*
X507200Y-1072833D01*
X507360Y-1072875D01*
X507520Y-1073000D01*
G01X509000Y-1073375D02*
X509853D01*
X509773Y-1073083D01*
X509640Y-1072917D01*
X509453Y-1072833D01*
X509267Y-1072875D01*
X509107Y-1073000D01*
X509000Y-1073292D01*
X508947Y-1073542D01*
Y-1073792D01*
X509000Y-1074042D01*
X509133Y-1074292D01*
X509293Y-1074458D01*
X509480Y-1074500D01*
X509667Y-1074417D01*
X509853Y-1074167D01*
G01X511120Y-1074500D02*
Y-1072000D01*
G01Y-1073250D02*
X511253Y-1073000D01*
X511413Y-1072875D01*
X511573Y-1072833D01*
X511813Y-1072917D01*
X511973Y-1073083D01*
X512080Y-1073375D01*
Y-1073708D01*
X512027Y-1074042D01*
X511920Y-1074292D01*
X511733Y-1074458D01*
X511573Y-1074500D01*
X511413Y-1074458D01*
X511253Y-1074333D01*
X511120Y-1074125D01*
G01X513800Y-1074500D02*
X513640Y-1074458D01*
X513480Y-1074292D01*
X513373Y-1074000D01*
X513320Y-1073667D01*
X513373Y-1073333D01*
X513480Y-1073042D01*
X513640Y-1072875D01*
X513800Y-1072833D01*
X513960Y-1072875D01*
X514120Y-1073042D01*
X514227Y-1073333D01*
X514253Y-1073667D01*
X514227Y-1074000D01*
X514120Y-1074292D01*
X513960Y-1074458D01*
X513800Y-1074500D01*
G01X516480D02*
Y-1072833D01*
G01Y-1073125D02*
X516373Y-1072958D01*
X516213Y-1072875D01*
X516027Y-1072833D01*
X515840Y-1072917D01*
X515680Y-1073083D01*
X515573Y-1073333D01*
X515520Y-1073667D01*
X515573Y-1074000D01*
X515680Y-1074250D01*
X515840Y-1074417D01*
X516027Y-1074500D01*
X516213Y-1074458D01*
X516373Y-1074333D01*
X516480Y-1074167D01*
G01X517827Y-1074500D02*
Y-1072833D01*
G01Y-1073167D02*
X517960Y-1073000D01*
X518093Y-1072875D01*
X518280Y-1072833D01*
X518413Y-1072875D01*
X518573Y-1073000D01*
G01X520880Y-1072000D02*
Y-1074500D01*
G01Y-1074125D02*
X520773Y-1074333D01*
X520613Y-1074458D01*
X520427Y-1074500D01*
X520213Y-1074417D01*
X520053Y-1074208D01*
X519947Y-1073958D01*
X519920Y-1073667D01*
X519947Y-1073375D01*
X520053Y-1073125D01*
X520213Y-1072917D01*
X520427Y-1072833D01*
X520613Y-1072875D01*
X520747Y-1072958D01*
X520880Y-1073125D01*
G01X524267Y-1074500D02*
Y-1072000D01*
X524933D01*
X525147Y-1072125D01*
X525280Y-1072292D01*
X525333Y-1072625D01*
X525280Y-1072958D01*
X525120Y-1073167D01*
X524933Y-1073292D01*
X524267D01*
G01X524933D02*
X525333Y-1074500D01*
G01X526600Y-1073375D02*
X527453D01*
X527373Y-1073083D01*
X527240Y-1072917D01*
X527053Y-1072833D01*
X526867Y-1072875D01*
X526707Y-1073000D01*
X526600Y-1073292D01*
X526547Y-1073542D01*
Y-1073792D01*
X526600Y-1074042D01*
X526733Y-1074292D01*
X526893Y-1074458D01*
X527080Y-1074500D01*
X527267Y-1074417D01*
X527453Y-1074167D01*
G01X528720Y-1072833D02*
X529200Y-1074500D01*
X529680Y-1072833D01*
G01X531400Y-1074583D02*
X531347Y-1074542D01*
Y-1074458D01*
X531400Y-1074417D01*
X531453Y-1074458D01*
Y-1074542D01*
X531400Y-1074583D01*
G01X533600Y-1074500D02*
X533787Y-1074458D01*
X534000Y-1074333D01*
X534133Y-1074125D01*
X534187Y-1073833D01*
X534133Y-1073542D01*
X533973Y-1073292D01*
X533733Y-1073167D01*
X533467D01*
X533307Y-1073083D01*
X533173Y-1072875D01*
X533120Y-1072583D01*
X533200Y-1072292D01*
X533387Y-1072083D01*
X533600Y-1072000D01*
X533813Y-1072083D01*
X534000Y-1072292D01*
X534080Y-1072583D01*
X534027Y-1072875D01*
X533893Y-1073083D01*
X533733Y-1073167D01*
X533467D01*
X533227Y-1073292D01*
X533067Y-1073542D01*
X533013Y-1073833D01*
X533067Y-1074125D01*
X533200Y-1074333D01*
X533413Y-1074458D01*
X533600Y-1074500D01*
G01X536013Y-1073167D02*
X536120Y-1073042D01*
X536200Y-1072833D01*
X536253Y-1072542D01*
X536200Y-1072292D01*
X536093Y-1072125D01*
X535907Y-1072000D01*
X535187D01*
Y-1074500D01*
X536067D01*
X536253Y-1074333D01*
X536360Y-1074083D01*
X536413Y-1073792D01*
X536360Y-1073500D01*
X536200Y-1073250D01*
X536013Y-1073167D01*
X535187D01*
G01X-457143Y-1211429D02*
Y2242857D01*
X4308572D01*
Y-1211429D01*
X-457143D01*
G01X71650Y-1024800D02*
X69130Y-1024383D01*
X66925Y-1022717D01*
X65035Y-1020217D01*
X63775Y-1017300D01*
X63145Y-1013967D01*
Y-1010633D01*
X63775Y-1007300D01*
X65035Y-1004383D01*
X66925Y-1001884D01*
X69130Y-1000217D01*
X71650Y-999800D01*
X74170Y-1000217D01*
X76375Y-1001884D01*
X78265Y-1004383D01*
X79525Y-1007300D01*
X80155Y-1010633D01*
Y-1013967D01*
X79525Y-1017300D01*
X78265Y-1020217D01*
X76375Y-1022717D01*
X74170Y-1024383D01*
X71650Y-1024800D01*
G01X74170Y-1018133D02*
X77950Y-1024800D01*
G01X91495Y-1008134D02*
Y-1019800D01*
X92755Y-1022717D01*
X94645Y-1024383D01*
X96850Y-1024800D01*
X99055Y-1024383D01*
X100945Y-1022717D01*
X102205Y-1019800D01*
G01Y-1024800D02*
Y-1008134D01*
G01X127720Y-1024800D02*
Y-1008134D01*
G01Y-1011050D02*
X126460Y-1009384D01*
X124570Y-1008550D01*
X122365Y-1008134D01*
X120160Y-1008967D01*
X118270Y-1010633D01*
X117010Y-1013134D01*
X116380Y-1016467D01*
X117010Y-1019800D01*
X118270Y-1022301D01*
X120160Y-1023967D01*
X122365Y-1024800D01*
X124570Y-1024383D01*
X126460Y-1023134D01*
X127720Y-1021467D01*
G01X141895Y-1024800D02*
Y-1008134D01*
G01Y-1012300D02*
X143155Y-1010217D01*
X145045Y-1008550D01*
X147565Y-1008134D01*
X149770Y-1008550D01*
X151660Y-1010217D01*
X152605Y-1013134D01*
Y-1024800D01*
G01X172450Y-999800D02*
Y-1024800D01*
G01X168040Y-1008134D02*
X176860D01*
G01X203320Y-1024800D02*
Y-1008134D01*
G01Y-1011050D02*
X202060Y-1009384D01*
X200170Y-1008550D01*
X197965Y-1008134D01*
X195760Y-1008967D01*
X193870Y-1010633D01*
X192610Y-1013134D01*
X191980Y-1016467D01*
X192610Y-1019800D01*
X193870Y-1022301D01*
X195760Y-1023967D01*
X197965Y-1024800D01*
X200170Y-1024383D01*
X202060Y-1023134D01*
X203320Y-1021467D01*
G01X49820Y-1042350D02*
X51387D01*
Y-1044240D01*
X50917Y-1044870D01*
X50368Y-1045290D01*
X49585Y-1045500D01*
X48802Y-1045290D01*
X48253Y-1044870D01*
X47783Y-1044240D01*
X47470Y-1043505D01*
X47313Y-1042665D01*
Y-1041930D01*
X47470Y-1041300D01*
X47783Y-1040565D01*
X48253Y-1039935D01*
X48723Y-1039515D01*
X49350Y-1039200D01*
X49898D01*
X50525Y-1039410D01*
X50995Y-1039830D01*
G01X53927Y-1039200D02*
Y-1043715D01*
X54240Y-1044660D01*
X54867Y-1045290D01*
X55650Y-1045500D01*
X56433Y-1045290D01*
X57060Y-1044660D01*
X57373Y-1043715D01*
Y-1039200D01*
G01X61010D02*
X62890D01*
G01X61950D02*
Y-1045500D01*
G01X61010D02*
X62890D01*
G01X66605Y-1044660D02*
X67232Y-1045185D01*
X67937Y-1045500D01*
X68563D01*
X69190Y-1045185D01*
X69660Y-1044660D01*
X69895Y-1043925D01*
X69738Y-1043190D01*
X69347Y-1042560D01*
X68642Y-1042140D01*
X67702Y-1041930D01*
X67153Y-1041510D01*
X66918Y-1040775D01*
X67075Y-1040040D01*
X67467Y-1039515D01*
X68015Y-1039200D01*
X68563D01*
X69112Y-1039410D01*
X69582Y-1039935D01*
G01X72905Y-1045500D02*
Y-1039200D01*
G01X76195D02*
Y-1045500D01*
G01Y-1042350D02*
X72905D01*
G01X78892Y-1045500D02*
X80850Y-1039200D01*
X82808Y-1045500D01*
G01X82103Y-1043295D02*
X79597D01*
G01X85348Y-1045500D02*
Y-1039200D01*
X88952Y-1045500D01*
Y-1039200D01*
G01X98027Y-1045500D02*
Y-1039200D01*
X99593D01*
X100220Y-1039515D01*
X100690Y-1039935D01*
X101082Y-1040565D01*
X101395Y-1041300D01*
X101473Y-1042350D01*
X101395Y-1043400D01*
X101082Y-1044135D01*
X100690Y-1044765D01*
X100220Y-1045185D01*
X99593Y-1045500D01*
X98027D01*
G01X105110Y-1039200D02*
X106990D01*
G01X106050D02*
Y-1045500D01*
G01X105110D02*
X106990D01*
G01X110705Y-1044660D02*
X111332Y-1045185D01*
X112037Y-1045500D01*
X112663D01*
X113290Y-1045185D01*
X113760Y-1044660D01*
X113995Y-1043925D01*
X113838Y-1043190D01*
X113447Y-1042560D01*
X112742Y-1042140D01*
X111802Y-1041930D01*
X111253Y-1041510D01*
X111018Y-1040775D01*
X111175Y-1040040D01*
X111567Y-1039515D01*
X112115Y-1039200D01*
X112663D01*
X113212Y-1039410D01*
X113682Y-1039935D01*
G01X118650Y-1039200D02*
Y-1045500D01*
G01X116848Y-1039200D02*
X120452D01*
G01X124950Y-1045710D02*
X124793Y-1045605D01*
Y-1045395D01*
X124950Y-1045290D01*
X125107Y-1045395D01*
Y-1045605D01*
X124950Y-1045710D01*
G01X131093Y-1046655D02*
X131407Y-1045290D01*
G01X137550Y-1039200D02*
Y-1045500D01*
G01X135748Y-1039200D02*
X139352D01*
G01X141892Y-1045500D02*
X143850Y-1039200D01*
X145808Y-1045500D01*
G01X145103Y-1043295D02*
X142597D01*
G01X150150Y-1045500D02*
X149523Y-1045395D01*
X148975Y-1044975D01*
X148505Y-1044345D01*
X148192Y-1043610D01*
X148035Y-1042770D01*
Y-1041930D01*
X148192Y-1041090D01*
X148505Y-1040355D01*
X148975Y-1039725D01*
X149523Y-1039305D01*
X150150Y-1039200D01*
X150777Y-1039305D01*
X151325Y-1039725D01*
X151795Y-1040355D01*
X152108Y-1041090D01*
X152265Y-1041930D01*
Y-1042770D01*
X152108Y-1043610D01*
X151795Y-1044345D01*
X151325Y-1044975D01*
X150777Y-1045395D01*
X150150Y-1045500D01*
G01X156450D02*
Y-1042665D01*
X154883Y-1039200D01*
G01X158017D02*
X156450Y-1042665D01*
G01X161027Y-1039200D02*
Y-1043715D01*
X161340Y-1044660D01*
X161967Y-1045290D01*
X162750Y-1045500D01*
X163533Y-1045290D01*
X164160Y-1044660D01*
X164473Y-1043715D01*
Y-1039200D01*
G01X167092Y-1045500D02*
X169050Y-1039200D01*
X171008Y-1045500D01*
G01X170303Y-1043295D02*
X167797D01*
G01X173548Y-1045500D02*
Y-1039200D01*
X177152Y-1045500D01*
Y-1039200D01*
G01X51073Y-1049725D02*
X50603Y-1049410D01*
X50055Y-1049200D01*
X49428D01*
X48723Y-1049515D01*
X48175Y-1050040D01*
X47783Y-1050670D01*
X47470Y-1051720D01*
X47392Y-1052665D01*
X47548Y-1053610D01*
X47783Y-1054240D01*
X48253Y-1054870D01*
X48802Y-1055290D01*
X49350Y-1055500D01*
X49898D01*
X50447Y-1055290D01*
X50917Y-1054975D01*
X51308Y-1054555D01*
G01X54710Y-1049200D02*
X56590D01*
G01X55650D02*
Y-1055500D01*
G01X54710D02*
X56590D01*
G01X61950Y-1049200D02*
Y-1055500D01*
G01X60148Y-1049200D02*
X63752D01*
G01X68250Y-1055500D02*
Y-1052665D01*
X66683Y-1049200D01*
G01X69817D02*
X68250Y-1052665D01*
G01X79127Y-1054240D02*
X79597Y-1054975D01*
X80223Y-1055395D01*
X80928Y-1055500D01*
X81555Y-1055395D01*
X82182Y-1054870D01*
X82573Y-1054240D01*
X82652Y-1053610D01*
X82495Y-1052875D01*
X81947Y-1052350D01*
X81398Y-1052140D01*
X80693D01*
G01X81398D02*
X81868Y-1051825D01*
X82260Y-1051300D01*
X82417Y-1050670D01*
X82260Y-1050040D01*
X81868Y-1049515D01*
X81163Y-1049200D01*
X80458Y-1049305D01*
X79753Y-1049725D01*
G01X85427Y-1054240D02*
X85897Y-1054975D01*
X86523Y-1055395D01*
X87228Y-1055500D01*
X87855Y-1055395D01*
X88482Y-1054870D01*
X88873Y-1054240D01*
X88952Y-1053610D01*
X88795Y-1052875D01*
X88247Y-1052350D01*
X87698Y-1052140D01*
X86993D01*
G01X87698D02*
X88168Y-1051825D01*
X88560Y-1051300D01*
X88717Y-1050670D01*
X88560Y-1050040D01*
X88168Y-1049515D01*
X87463Y-1049200D01*
X86758Y-1049305D01*
X86053Y-1049725D01*
G01X91727Y-1054240D02*
X92197Y-1054975D01*
X92823Y-1055395D01*
X93528Y-1055500D01*
X94155Y-1055395D01*
X94782Y-1054870D01*
X95173Y-1054240D01*
X95252Y-1053610D01*
X95095Y-1052875D01*
X94547Y-1052350D01*
X93998Y-1052140D01*
X93293D01*
G01X93998D02*
X94468Y-1051825D01*
X94860Y-1051300D01*
X95017Y-1050670D01*
X94860Y-1050040D01*
X94468Y-1049515D01*
X93763Y-1049200D01*
X93058Y-1049305D01*
X92353Y-1049725D01*
G01X99593Y-1055500D02*
X99750Y-1054135D01*
X99985Y-1052980D01*
X100298Y-1051930D01*
X100690Y-1050775D01*
X101317Y-1049200D01*
X98183D01*
G01X105893Y-1055500D02*
X106050Y-1054135D01*
X106285Y-1052980D01*
X106598Y-1051930D01*
X106990Y-1050775D01*
X107617Y-1049200D01*
X104483D01*
G01X112193Y-1056655D02*
X112507Y-1055290D01*
G01X118650Y-1049200D02*
Y-1055500D01*
G01X116848Y-1049200D02*
X120452D01*
G01X122992Y-1055500D02*
X124950Y-1049200D01*
X126908Y-1055500D01*
G01X126203Y-1053295D02*
X123697D01*
G01X130310Y-1049200D02*
X132190D01*
G01X131250D02*
Y-1055500D01*
G01X130310D02*
X132190D01*
G01X135200Y-1049200D02*
X136297Y-1055500D01*
X137550Y-1049200D01*
X138803Y-1055500D01*
X139900Y-1049200D01*
G01X141892Y-1055500D02*
X143850Y-1049200D01*
X145808Y-1055500D01*
G01X145103Y-1053295D02*
X142597D01*
G01X148348Y-1055500D02*
Y-1049200D01*
X151952Y-1055500D01*
Y-1049200D01*
G01X162358Y-1057600D02*
X161575Y-1056550D01*
X161183Y-1055500D01*
Y-1051300D01*
X161575Y-1050250D01*
X162358Y-1049200D01*
G01X173783Y-1055500D02*
Y-1049200D01*
X175742D01*
X176368Y-1049515D01*
X176760Y-1049935D01*
X176917Y-1050775D01*
X176760Y-1051615D01*
X176290Y-1052140D01*
X175742Y-1052455D01*
X173783D01*
G01X175742D02*
X176917Y-1055500D01*
G01X181650Y-1055710D02*
X181493Y-1055605D01*
Y-1055395D01*
X181650Y-1055290D01*
X181807Y-1055395D01*
Y-1055605D01*
X181650Y-1055710D01*
G01X187950Y-1055500D02*
X187323Y-1055395D01*
X186775Y-1054975D01*
X186305Y-1054345D01*
X185992Y-1053610D01*
X185835Y-1052770D01*
Y-1051930D01*
X185992Y-1051090D01*
X186305Y-1050355D01*
X186775Y-1049725D01*
X187323Y-1049305D01*
X187950Y-1049200D01*
X188577Y-1049305D01*
X189125Y-1049725D01*
X189595Y-1050355D01*
X189908Y-1051090D01*
X190065Y-1051930D01*
Y-1052770D01*
X189908Y-1053610D01*
X189595Y-1054345D01*
X189125Y-1054975D01*
X188577Y-1055395D01*
X187950Y-1055500D01*
G01X194250Y-1055710D02*
X194093Y-1055605D01*
Y-1055395D01*
X194250Y-1055290D01*
X194407Y-1055395D01*
Y-1055605D01*
X194250Y-1055710D01*
G01X202273Y-1049725D02*
X201803Y-1049410D01*
X201255Y-1049200D01*
X200628D01*
X199923Y-1049515D01*
X199375Y-1050040D01*
X198983Y-1050670D01*
X198670Y-1051720D01*
X198592Y-1052665D01*
X198748Y-1053610D01*
X198983Y-1054240D01*
X199453Y-1054870D01*
X200002Y-1055290D01*
X200550Y-1055500D01*
X201098D01*
X201647Y-1055290D01*
X202117Y-1054975D01*
X202508Y-1054555D01*
G01X206850Y-1055710D02*
X206693Y-1055605D01*
Y-1055395D01*
X206850Y-1055290D01*
X207007Y-1055395D01*
Y-1055605D01*
X206850Y-1055710D01*
G01X213542Y-1057600D02*
X214325Y-1056550D01*
X214717Y-1055500D01*
Y-1051300D01*
X214325Y-1050250D01*
X213542Y-1049200D01*
G01X47548Y-1035500D02*
Y-1029200D01*
X51152Y-1035500D01*
Y-1029200D01*
G01X55650Y-1035500D02*
X55023Y-1035395D01*
X54475Y-1034975D01*
X54005Y-1034345D01*
X53692Y-1033610D01*
X53535Y-1032770D01*
Y-1031930D01*
X53692Y-1031090D01*
X54005Y-1030355D01*
X54475Y-1029725D01*
X55023Y-1029305D01*
X55650Y-1029200D01*
X56277Y-1029305D01*
X56825Y-1029725D01*
X57295Y-1030355D01*
X57608Y-1031090D01*
X57765Y-1031930D01*
Y-1032770D01*
X57608Y-1033610D01*
X57295Y-1034345D01*
X56825Y-1034975D01*
X56277Y-1035395D01*
X55650Y-1035500D01*
G01X61950Y-1035710D02*
X61793Y-1035605D01*
Y-1035395D01*
X61950Y-1035290D01*
X62107Y-1035395D01*
Y-1035605D01*
X61950Y-1035710D01*
G01X66762Y-1030250D02*
X67232Y-1029620D01*
X67780Y-1029305D01*
X68407Y-1029200D01*
X69190Y-1029410D01*
X69738Y-1029935D01*
X69895Y-1030565D01*
X69817Y-1031195D01*
X69503Y-1031720D01*
X67937Y-1032770D01*
X67232Y-1033505D01*
X66762Y-1034555D01*
X66605Y-1035500D01*
X69895D01*
G01X74550D02*
Y-1029200D01*
X73610Y-1030460D01*
G01Y-1035500D02*
X75490D01*
G01X80850D02*
Y-1029200D01*
X79910Y-1030460D01*
G01Y-1035500D02*
X81790D01*
G01X86993Y-1036655D02*
X87307Y-1035290D01*
G01X91100Y-1029200D02*
X92197Y-1035500D01*
X93450Y-1029200D01*
X94703Y-1035500D01*
X95800Y-1029200D01*
G01X101317Y-1035500D02*
X98183D01*
Y-1029200D01*
X101317D01*
G01X100063Y-1032245D02*
X98183D01*
G01X104248Y-1035500D02*
Y-1029200D01*
X107852Y-1035500D01*
Y-1029200D01*
G01X110705Y-1035500D02*
Y-1029200D01*
G01X113995D02*
Y-1035500D01*
G01Y-1032350D02*
X110705D01*
G01X116927Y-1029200D02*
Y-1033715D01*
X117240Y-1034660D01*
X117867Y-1035290D01*
X118650Y-1035500D01*
X119433Y-1035290D01*
X120060Y-1034660D01*
X120373Y-1033715D01*
Y-1029200D01*
G01X122992Y-1035500D02*
X124950Y-1029200D01*
X126908Y-1035500D01*
G01X126203Y-1033295D02*
X123697D01*
G01X136062Y-1030250D02*
X136532Y-1029620D01*
X137080Y-1029305D01*
X137707Y-1029200D01*
X138490Y-1029410D01*
X139038Y-1029935D01*
X139195Y-1030565D01*
X139117Y-1031195D01*
X138803Y-1031720D01*
X137237Y-1032770D01*
X136532Y-1033505D01*
X136062Y-1034555D01*
X135905Y-1035500D01*
X139195D01*
G01X142048D02*
Y-1029200D01*
X145652Y-1035500D01*
Y-1029200D01*
G01X148427Y-1035500D02*
Y-1029200D01*
X149993D01*
X150620Y-1029515D01*
X151090Y-1029935D01*
X151482Y-1030565D01*
X151795Y-1031300D01*
X151873Y-1032350D01*
X151795Y-1033400D01*
X151482Y-1034135D01*
X151090Y-1034765D01*
X150620Y-1035185D01*
X149993Y-1035500D01*
X148427D01*
G01X161183D02*
Y-1029200D01*
X163142D01*
X163768Y-1029515D01*
X164160Y-1029935D01*
X164317Y-1030775D01*
X164160Y-1031615D01*
X163690Y-1032140D01*
X163142Y-1032455D01*
X161183D01*
G01X163142D02*
X164317Y-1035500D01*
G01X167327D02*
Y-1029200D01*
X168893D01*
X169520Y-1029515D01*
X169990Y-1029935D01*
X170382Y-1030565D01*
X170695Y-1031300D01*
X170773Y-1032350D01*
X170695Y-1033400D01*
X170382Y-1034135D01*
X169990Y-1034765D01*
X169520Y-1035185D01*
X168893Y-1035500D01*
X167327D01*
G01X175350Y-1035710D02*
X175193Y-1035605D01*
Y-1035395D01*
X175350Y-1035290D01*
X175507Y-1035395D01*
Y-1035605D01*
X175350Y-1035710D01*
G01X243000Y-1004500D02*
Y-1012500D01*
X247000D01*
G01X254800D02*
Y-1007167D01*
G01Y-1008100D02*
X254400Y-1007567D01*
X253800Y-1007300D01*
X253100Y-1007167D01*
X252400Y-1007433D01*
X251800Y-1007967D01*
X251400Y-1008767D01*
X251200Y-1009833D01*
X251400Y-1010900D01*
X251800Y-1011700D01*
X252400Y-1012233D01*
X253100Y-1012500D01*
X253800Y-1012367D01*
X254400Y-1011967D01*
X254800Y-1011434D01*
G01X258900Y-1014900D02*
X259500Y-1015167D01*
X260300Y-1014900D01*
X260800Y-1014367D01*
X261200Y-1013700D01*
X261800Y-1011567D01*
X263100Y-1007167D01*
G01X259900D02*
X261800Y-1011567D01*
G01X267500Y-1008900D02*
X270700D01*
X270400Y-1007967D01*
X269900Y-1007433D01*
X269200Y-1007167D01*
X268500Y-1007300D01*
X267900Y-1007700D01*
X267500Y-1008633D01*
X267300Y-1009434D01*
Y-1010233D01*
X267500Y-1011033D01*
X268000Y-1011833D01*
X268600Y-1012367D01*
X269300Y-1012500D01*
X270000Y-1012233D01*
X270700Y-1011434D01*
G01X275600Y-1012500D02*
Y-1007167D01*
G01Y-1008233D02*
X276100Y-1007700D01*
X276600Y-1007300D01*
X277300Y-1007167D01*
X277800Y-1007300D01*
X278400Y-1007700D01*
G01X262100Y-1054500D02*
X265900D01*
X262100Y-1062500D01*
X265900D01*
G01X272000Y-1057167D02*
Y-1062500D01*
G01Y-1055033D02*
X271800Y-1054900D01*
Y-1054633D01*
X272000Y-1054500D01*
X272200Y-1054633D01*
Y-1054900D01*
X272000Y-1055033D01*
G01X278700Y-1059833D02*
X281300D01*
G01X286200Y-1065167D02*
Y-1057167D01*
G01Y-1058367D02*
X286700Y-1057700D01*
X287200Y-1057300D01*
X288000Y-1057167D01*
X288700Y-1057300D01*
X289400Y-1057967D01*
X289700Y-1058900D01*
X289800Y-1059833D01*
X289700Y-1060767D01*
X289400Y-1061700D01*
X288800Y-1062233D01*
X288000Y-1062500D01*
X287300Y-1062367D01*
X286600Y-1061967D01*
X286200Y-1061434D01*
G01X296000Y-1057167D02*
Y-1062500D01*
G01Y-1055033D02*
X295800Y-1054900D01*
Y-1054633D01*
X296000Y-1054500D01*
X296200Y-1054633D01*
Y-1054900D01*
X296000Y-1055033D01*
G01X302300Y-1062500D02*
Y-1057167D01*
G01Y-1058500D02*
X302700Y-1057833D01*
X303300Y-1057300D01*
X304100Y-1057167D01*
X304800Y-1057300D01*
X305400Y-1057833D01*
X305700Y-1058767D01*
Y-1062500D01*
G01X310600Y-1064500D02*
X311300Y-1065033D01*
X312100Y-1065167D01*
X312800Y-1065033D01*
X313400Y-1064367D01*
X313800Y-1063433D01*
Y-1057167D01*
G01Y-1058233D02*
X313400Y-1057700D01*
X312800Y-1057300D01*
X312100Y-1057167D01*
X311300Y-1057433D01*
X310800Y-1057967D01*
X310400Y-1058900D01*
X310200Y-1059833D01*
X310300Y-1060633D01*
X310700Y-1061567D01*
X311300Y-1062233D01*
X312100Y-1062500D01*
X312700Y-1062367D01*
X313400Y-1061833D01*
X313800Y-1061300D01*
G01X267300Y-1033233D02*
X267700Y-1032833D01*
X268000Y-1032167D01*
X268200Y-1031233D01*
X268000Y-1030433D01*
X267600Y-1029900D01*
X266900Y-1029500D01*
X264200D01*
Y-1037500D01*
X267500D01*
X268200Y-1036967D01*
X268600Y-1036167D01*
X268800Y-1035233D01*
X268600Y-1034300D01*
X268000Y-1033500D01*
X267300Y-1033233D01*
X264200D01*
G01X274500Y-1037500D02*
X273700Y-1037367D01*
X273000Y-1036833D01*
X272400Y-1036033D01*
X272000Y-1035100D01*
X271800Y-1034033D01*
Y-1032967D01*
X272000Y-1031900D01*
X272400Y-1030967D01*
X273000Y-1030167D01*
X273700Y-1029633D01*
X274500Y-1029500D01*
X275300Y-1029633D01*
X276000Y-1030167D01*
X276600Y-1030967D01*
X277000Y-1031900D01*
X277200Y-1032967D01*
Y-1034033D01*
X277000Y-1035100D01*
X276600Y-1036033D01*
X276000Y-1036833D01*
X275300Y-1037367D01*
X274500Y-1037500D01*
G01X282500Y-1029500D02*
Y-1037500D01*
G01X280200Y-1029500D02*
X284800D01*
G01X290500D02*
Y-1037500D01*
G01X288200Y-1029500D02*
X292800D01*
G01X298500Y-1037500D02*
X297700Y-1037367D01*
X297000Y-1036833D01*
X296400Y-1036033D01*
X296000Y-1035100D01*
X295800Y-1034033D01*
Y-1032967D01*
X296000Y-1031900D01*
X296400Y-1030967D01*
X297000Y-1030167D01*
X297700Y-1029633D01*
X298500Y-1029500D01*
X299300Y-1029633D01*
X300000Y-1030167D01*
X300600Y-1030967D01*
X301000Y-1031900D01*
X301200Y-1032967D01*
Y-1034033D01*
X301000Y-1035100D01*
X300600Y-1036033D01*
X300000Y-1036833D01*
X299300Y-1037367D01*
X298500Y-1037500D01*
G01X303900D02*
Y-1029500D01*
X306500Y-1036167D01*
X309100Y-1029500D01*
Y-1037500D01*
G01X291500Y-1012500D02*
Y-1004500D01*
X290300Y-1006100D01*
G01Y-1012500D02*
X292700D01*
G01X299500Y-1004500D02*
X298700Y-1004767D01*
X298100Y-1005433D01*
X297700Y-1006233D01*
X297400Y-1007300D01*
X297300Y-1008500D01*
X297400Y-1009700D01*
X297700Y-1010767D01*
X298100Y-1011567D01*
X298700Y-1012233D01*
X299500Y-1012500D01*
X300300Y-1012233D01*
X300900Y-1011567D01*
X301300Y-1010767D01*
X301600Y-1009700D01*
X301700Y-1008500D01*
X301600Y-1007300D01*
X301300Y-1006233D01*
X300900Y-1005433D01*
X300300Y-1004767D01*
X299500Y-1004500D01*
G01X369600Y-1055833D02*
X370200Y-1055033D01*
X370900Y-1054633D01*
X371700Y-1054500D01*
X372700Y-1054767D01*
X373400Y-1055433D01*
X373600Y-1056233D01*
X373500Y-1057034D01*
X373100Y-1057700D01*
X371100Y-1059033D01*
X370200Y-1059967D01*
X369600Y-1061300D01*
X369400Y-1062500D01*
X373600D01*
G01X379500Y-1054500D02*
X378700Y-1054767D01*
X378100Y-1055433D01*
X377700Y-1056233D01*
X377400Y-1057300D01*
X377300Y-1058500D01*
X377400Y-1059700D01*
X377700Y-1060767D01*
X378100Y-1061567D01*
X378700Y-1062233D01*
X379500Y-1062500D01*
X380300Y-1062233D01*
X380900Y-1061567D01*
X381300Y-1060767D01*
X381600Y-1059700D01*
X381700Y-1058500D01*
X381600Y-1057300D01*
X381300Y-1056233D01*
X380900Y-1055433D01*
X380300Y-1054767D01*
X379500Y-1054500D01*
G01X385600Y-1055833D02*
X386200Y-1055033D01*
X386900Y-1054633D01*
X387700Y-1054500D01*
X388700Y-1054767D01*
X389400Y-1055433D01*
X389600Y-1056233D01*
X389500Y-1057034D01*
X389100Y-1057700D01*
X387100Y-1059033D01*
X386200Y-1059967D01*
X385600Y-1061300D01*
X385400Y-1062500D01*
X389600D01*
G01X393600Y-1055833D02*
X394200Y-1055033D01*
X394900Y-1054633D01*
X395700Y-1054500D01*
X396700Y-1054767D01*
X397400Y-1055433D01*
X397600Y-1056233D01*
X397500Y-1057034D01*
X397100Y-1057700D01*
X395100Y-1059033D01*
X394200Y-1059967D01*
X393600Y-1061300D01*
X393400Y-1062500D01*
X397600D01*
G01X401700Y-1062767D02*
X405300Y-1054500D01*
G01X411500Y-1062500D02*
Y-1054500D01*
X410300Y-1056100D01*
G01Y-1062500D02*
X412700D01*
G01X417600Y-1055833D02*
X418200Y-1055033D01*
X418900Y-1054633D01*
X419700Y-1054500D01*
X420700Y-1054767D01*
X421400Y-1055433D01*
X421600Y-1056233D01*
X421500Y-1057034D01*
X421100Y-1057700D01*
X419100Y-1059033D01*
X418200Y-1059967D01*
X417600Y-1061300D01*
X417400Y-1062500D01*
X421600D01*
G01X425700Y-1062767D02*
X429300Y-1054500D01*
G01X435500Y-1062500D02*
Y-1054500D01*
X434300Y-1056100D01*
G01Y-1062500D02*
X436700D01*
G01X441300Y-1060900D02*
X441900Y-1061833D01*
X442700Y-1062367D01*
X443600Y-1062500D01*
X444400Y-1062367D01*
X445200Y-1061700D01*
X445700Y-1060900D01*
X445800Y-1060100D01*
X445600Y-1059167D01*
X444900Y-1058500D01*
X444200Y-1058233D01*
X443300D01*
G01X444200D02*
X444800Y-1057833D01*
X445300Y-1057167D01*
X445500Y-1056367D01*
X445300Y-1055567D01*
X444800Y-1054900D01*
X443900Y-1054500D01*
X443000Y-1054633D01*
X442100Y-1055167D01*
G01X369300Y-1040000D02*
Y-1032000D01*
X371300D01*
X372100Y-1032400D01*
X372700Y-1032933D01*
X373200Y-1033733D01*
X373600Y-1034667D01*
X373700Y-1036000D01*
X373600Y-1037333D01*
X373200Y-1038267D01*
X372700Y-1039067D01*
X372100Y-1039600D01*
X371300Y-1040000D01*
X369300D01*
G01X377000D02*
X379500Y-1032000D01*
X382000Y-1040000D01*
G01X381100Y-1037200D02*
X377900D01*
G01X385600Y-1040000D02*
Y-1032000D01*
X389400D01*
G01X388000Y-1035867D02*
X385600D01*
G01X395500Y-1032000D02*
X394700Y-1032267D01*
X394100Y-1032933D01*
X393700Y-1033733D01*
X393400Y-1034800D01*
X393300Y-1036000D01*
X393400Y-1037200D01*
X393700Y-1038267D01*
X394100Y-1039067D01*
X394700Y-1039733D01*
X395500Y-1040000D01*
X396300Y-1039733D01*
X396900Y-1039067D01*
X397300Y-1038267D01*
X397600Y-1037200D01*
X397700Y-1036000D01*
X397600Y-1034800D01*
X397300Y-1033733D01*
X396900Y-1032933D01*
X396300Y-1032267D01*
X395500Y-1032000D01*
G01X403500D02*
Y-1040000D01*
G01X401200Y-1032000D02*
X405800D01*
G01X409500Y-1040000D02*
Y-1032000D01*
X411900D01*
X412700Y-1032400D01*
X413300Y-1033333D01*
X413500Y-1034400D01*
X413300Y-1035467D01*
X412800Y-1036267D01*
X411900Y-1036667D01*
X409500D01*
G01X420300Y-1035733D02*
X420700Y-1035333D01*
X421000Y-1034667D01*
X421200Y-1033733D01*
X421000Y-1032933D01*
X420600Y-1032400D01*
X419900Y-1032000D01*
X417200D01*
Y-1040000D01*
X420500D01*
X421200Y-1039467D01*
X421600Y-1038667D01*
X421800Y-1037733D01*
X421600Y-1036800D01*
X421000Y-1036000D01*
X420300Y-1035733D01*
X417200D01*
G01X427500Y-1040000D02*
Y-1032000D01*
X426300Y-1033600D01*
G01Y-1040000D02*
X428700D01*
G01X433000D02*
X435500Y-1032000D01*
X438000Y-1040000D01*
G01X437100Y-1037200D02*
X433900D01*
G01X441600Y-1040000D02*
Y-1032000D01*
X445400D01*
G01X444000Y-1035867D02*
X441600D01*
G01X451500Y-1032000D02*
X450700Y-1032267D01*
X450100Y-1032933D01*
X449700Y-1033733D01*
X449400Y-1034800D01*
X449300Y-1036000D01*
X449400Y-1037200D01*
X449700Y-1038267D01*
X450100Y-1039067D01*
X450700Y-1039733D01*
X451500Y-1040000D01*
X452300Y-1039733D01*
X452900Y-1039067D01*
X453300Y-1038267D01*
X453600Y-1037200D01*
X453700Y-1036000D01*
X453600Y-1034800D01*
X453300Y-1033733D01*
X452900Y-1032933D01*
X452300Y-1032267D01*
X451500Y-1032000D01*
G01X389600Y-1012500D02*
Y-1004500D01*
X393400D01*
G01X392000Y-1008367D02*
X389600D01*
G01X399500Y-1004500D02*
X398700Y-1004767D01*
X398100Y-1005433D01*
X397700Y-1006233D01*
X397400Y-1007300D01*
X397300Y-1008500D01*
X397400Y-1009700D01*
X397700Y-1010767D01*
X398100Y-1011567D01*
X398700Y-1012233D01*
X399500Y-1012500D01*
X400300Y-1012233D01*
X400900Y-1011567D01*
X401300Y-1010767D01*
X401600Y-1009700D01*
X401700Y-1008500D01*
X401600Y-1007300D01*
X401300Y-1006233D01*
X400900Y-1005433D01*
X400300Y-1004767D01*
X399500Y-1004500D01*
G01X407500D02*
Y-1012500D01*
G01X405200Y-1004500D02*
X409800D01*
G01X412500Y-1015167D02*
X418500D01*
G01X421500Y-1012500D02*
Y-1004500D01*
X423900D01*
X424700Y-1004900D01*
X425300Y-1005833D01*
X425500Y-1006900D01*
X425300Y-1007967D01*
X424800Y-1008767D01*
X423900Y-1009167D01*
X421500D01*
G01X429300Y-1012500D02*
Y-1004500D01*
X431300D01*
X432100Y-1004900D01*
X432700Y-1005433D01*
X433200Y-1006233D01*
X433600Y-1007167D01*
X433700Y-1008500D01*
X433600Y-1009833D01*
X433200Y-1010767D01*
X432700Y-1011567D01*
X432100Y-1012100D01*
X431300Y-1012500D01*
X429300D01*
G01X440300Y-1008233D02*
X440700Y-1007833D01*
X441000Y-1007167D01*
X441200Y-1006233D01*
X441000Y-1005433D01*
X440600Y-1004900D01*
X439900Y-1004500D01*
X437200D01*
Y-1012500D01*
X440500D01*
X441200Y-1011967D01*
X441600Y-1011167D01*
X441800Y-1010233D01*
X441600Y-1009300D01*
X441000Y-1008500D01*
X440300Y-1008233D01*
X437200D01*
G01X444500Y-1015167D02*
X450500D01*
G01X456300Y-1008233D02*
X456700Y-1007833D01*
X457000Y-1007167D01*
X457200Y-1006233D01*
X457000Y-1005433D01*
X456600Y-1004900D01*
X455900Y-1004500D01*
X453200D01*
Y-1012500D01*
X456500D01*
X457200Y-1011967D01*
X457600Y-1011167D01*
X457800Y-1010233D01*
X457600Y-1009300D01*
X457000Y-1008500D01*
X456300Y-1008233D01*
X453200D01*
G01X461300Y-1012500D02*
Y-1004500D01*
X463300D01*
X464100Y-1004900D01*
X464700Y-1005433D01*
X465200Y-1006233D01*
X465600Y-1007167D01*
X465700Y-1008500D01*
X465600Y-1009833D01*
X465200Y-1010767D01*
X464700Y-1011567D01*
X464100Y-1012100D01*
X463300Y-1012500D01*
X461300D01*
G01X468500Y-1015167D02*
X474500D01*
G01X480100Y-1008500D02*
X482100D01*
Y-1010900D01*
X481500Y-1011700D01*
X480800Y-1012233D01*
X479800Y-1012500D01*
X478800Y-1012233D01*
X478100Y-1011700D01*
X477500Y-1010900D01*
X477100Y-1009967D01*
X476900Y-1008900D01*
Y-1007967D01*
X477100Y-1007167D01*
X477500Y-1006233D01*
X478100Y-1005433D01*
X478700Y-1004900D01*
X479500Y-1004500D01*
X480200D01*
X481000Y-1004767D01*
X481600Y-1005300D01*
G01X485500Y-1012500D02*
Y-1004500D01*
X487900D01*
X488700Y-1004900D01*
X489300Y-1005833D01*
X489500Y-1006900D01*
X489300Y-1007967D01*
X488800Y-1008767D01*
X487900Y-1009167D01*
X485500D01*
G01X493300Y-1004500D02*
Y-1010233D01*
X493700Y-1011434D01*
X494500Y-1012233D01*
X495500Y-1012500D01*
X496500Y-1012233D01*
X497300Y-1011434D01*
X497700Y-1010233D01*
Y-1004500D01*
G01X458000Y-1065500D02*
Y-1057500D01*
X456800Y-1059100D01*
G01Y-1065500D02*
X459200D01*
G01X464100Y-1062167D02*
X464800Y-1061233D01*
X465400Y-1060700D01*
X466200Y-1060433D01*
X466900Y-1060700D01*
X467400Y-1061233D01*
X467800Y-1062033D01*
X467900Y-1062967D01*
X467800Y-1063767D01*
X467400Y-1064567D01*
X466800Y-1065233D01*
X466100Y-1065500D01*
X465300Y-1065233D01*
X464600Y-1064434D01*
X464200Y-1063233D01*
X464100Y-1061900D01*
X464300Y-1060167D01*
X464600Y-1059233D01*
X465100Y-1058300D01*
X465800Y-1057633D01*
X466500Y-1057500D01*
X467200Y-1057767D01*
X467700Y-1058433D01*
G01X474000Y-1065767D02*
X473800Y-1065633D01*
Y-1065367D01*
X474000Y-1065233D01*
X474200Y-1065367D01*
Y-1065633D01*
X474000Y-1065767D01*
G01X480100Y-1062167D02*
X480800Y-1061233D01*
X481400Y-1060700D01*
X482200Y-1060433D01*
X482900Y-1060700D01*
X483400Y-1061233D01*
X483800Y-1062033D01*
X483900Y-1062967D01*
X483800Y-1063767D01*
X483400Y-1064567D01*
X482800Y-1065233D01*
X482100Y-1065500D01*
X481300Y-1065233D01*
X480600Y-1064434D01*
X480200Y-1063233D01*
X480100Y-1061900D01*
X480300Y-1060167D01*
X480600Y-1059233D01*
X481100Y-1058300D01*
X481800Y-1057633D01*
X482500Y-1057500D01*
X483200Y-1057767D01*
X483700Y-1058433D01*
G01X503000Y-1065500D02*
Y-1057500D01*
X501800Y-1059100D01*
G01Y-1065500D02*
X504200D01*
G01X510800D02*
X511000Y-1063767D01*
X511300Y-1062300D01*
X511700Y-1060967D01*
X512200Y-1059500D01*
X513000Y-1057500D01*
X509000D01*
G01X519000Y-1065767D02*
X518800Y-1065633D01*
Y-1065367D01*
X519000Y-1065233D01*
X519200Y-1065367D01*
Y-1065633D01*
X519000Y-1065767D01*
G01X525100Y-1058833D02*
X525700Y-1058033D01*
X526400Y-1057633D01*
X527200Y-1057500D01*
X528200Y-1057767D01*
X528900Y-1058433D01*
X529100Y-1059233D01*
X529000Y-1060034D01*
X528600Y-1060700D01*
X526600Y-1062033D01*
X525700Y-1062967D01*
X525100Y-1064300D01*
X524900Y-1065500D01*
X529100D01*
G01X523100Y-1040500D02*
Y-1032500D01*
X526900D01*
G01X525500Y-1036367D02*
X523100D01*
M02*
